FILE_TYPE = MACRO_DRAWING;
SET COLOR_WIRE YELLOW;
SET COLOR_PROP ORANGE;
SET COLOR_DOT WHITE;
SET COLOR_ARC YELLOW;
SET COLOR_BODY GREEN;
SET COLOR_NOTE PURPLE;
SET PROP_DISPLAY VALUE;
SET PAGE_NUMBER P303;
FORCEADD UNIVERSAL_GND..1
(-17225 175);
FORCEPROP 3 LASTPIN (-17225 225) SIG_NAME GND\g
J 0
(-17215 235);
DISPLAY 0.659574 (-17215 235);
PAINT MONO (-17215 235);
DISPLAY INVISIBLE (-17215 235);
FORCEPROP 1 LAST HDL_POWER GND
J 1
(-17200 100);
DISPLAY 0.872340 (-17200 100);
PAINT GREEN (-17200 100);
DISPLAY INVISIBLE (-17200 100);
FORCEPROP 2 LAST CDS_LIB logical_power
J 0
(-17225 175);
DISPLAY INVISIBLE (-17225 175);
FORCEPROP 1 LAST PATH I1
J 0
(-17150 175);
DISPLAY 0.872340 (-17150 175);
PAINT AQUA (-17150 175);
DISPLAY INVISIBLE (-17150 175);
FORCEADD Q_RES..2
(-16575 950);
FORCEPROP 1 LAST PART_NUMBER CS36342FB04
J 0
(-16525 875);
DISPLAY 0.723404 (-16525 875);
PAINT WHITE (-16525 875);
DISPLAY INVISIBLE (-16525 875);
FORCEPROP 1 LAST PACK_TYPE 0402LF
J 0
(-16525 825);
DISPLAY 0.723404 (-16525 825);
PAINT SKYBLUE (-16525 825);
FORCEPROP 1 LAST VALUE 63.4K
J 0
(-16530 1025);
DISPLAY 0.723404 (-16530 1025);
PAINT SKYBLUE (-16530 1025);
FORCEPROP 1 LAST TOLERANCE 1%
J 0
(-16530 975);
DISPLAY 0.723404 (-16530 975);
PAINT SKYBLUE (-16530 975);
FORCEPROP 1 LAST WATTAGE 1/16W
J 0
(-16535 925);
DISPLAY 0.723404 (-16535 925);
PAINT SKYBLUE (-16535 925);
FORCEPROP 1 LAST LOCATION R3923
J 0
(-16530 1075);
DISPLAY 0.723404 (-16530 1075);
PAINT AQUA (-16530 1075);
FORCEPROP 1 LASTPIN (-16575 1050) $PN 1
J 0
(-16570 1012);
DISPLAY 0.787234 (-16570 1012);
PAINT MONO (-16570 1012);
FORCEPROP 1 LASTPIN (-16575 850) $PN 2
J 0
(-16570 860);
DISPLAY 0.787234 (-16570 860);
PAINT MONO (-16570 860);
FORCEPROP 1 LAST MATERIAL CHIP
J 0
(-16535 875);
DISPLAY 0.723404 (-16535 875);
PAINT SKYBLUE (-16535 875);
DISPLAY INVISIBLE (-16535 875);
FORCEPROP 2 LAST CDS_LIB pure_quanta
J 0
(-16575 950);
DISPLAY INVISIBLE (-16575 950);
FORCEPROP 1 LAST PATH I10
J 0
(-16525 1125);
DISPLAY 0.978723 (-16525 1125);
PAINT WHITE (-16525 1125);
DISPLAY INVISIBLE (-16525 1125);
FORCEPROP 0 LAST $SEC 1
J 0
(-16525 1125);
DISPLAY 0.680851 (-16525 1125);
PAINT MONO (-16525 1125);
DISPLAY INVISIBLE (-16525 1125);
FORCEPROP 0 LAST CDS_SEC 1
J 0
(-16525 1125);
DISPLAY 1.021277 (-16525 1125);
DISPLAY INVISIBLE (-16525 1125);
FORCEADD GND..1
(-16800 1600);
FORCEPROP 3 LASTPIN (-16800 1650) SIG_NAME GND\g
J 0
(-16790 1660);
DISPLAY 0.659574 (-16790 1660);
PAINT MONO (-16790 1660);
DISPLAY INVISIBLE (-16790 1660);
FORCEPROP 1 LAST HDL_POWER GND
J 0
(-16800 1750);
DISPLAY 1.170213 (-16800 1750);
PAINT GREEN (-16800 1750);
DISPLAY INVISIBLE (-16800 1750);
FORCEPROP 2 LAST CDS_LIB logical_power
J 0
(-16800 1600);
DISPLAY INVISIBLE (-16800 1600);
FORCEPROP 1 LAST SIZE 1B
J 0
(-16725 1550);
DISPLAY 0.872340 (-16725 1550);
PAINT AQUA (-16725 1550);
DISPLAY INVISIBLE (-16725 1550);
FORCEPROP 1 LAST PATH I11
J 0
(-16725 1600);
DISPLAY 0.872340 (-16725 1600);
PAINT AQUA (-16725 1600);
DISPLAY INVISIBLE (-16725 1600);
FORCEADD CONN3_210HP1030BR1..1
(-16550 1800);
PAINT AQUA (-16550 1800);
FORCEPROP 1 LAST PART_NUMBER DFHD03MS213
J 0
(-16600 1975);
DISPLAY 0.723404 (-16600 1975);
PAINT WHITE (-16600 1975);
DISPLAY INVISIBLE (-16600 1975);
FORCEPROP 1 LAST MATERIAL IO
J 0
(-16613 1924);
DISPLAY 0.723404 (-16613 1924);
PAINT SKYBLUE (-16613 1924);
FORCEPROP 2 LAST PART_TYPE THLF
J 0
(-16600 2125);
DISPLAY 1.021277 (-16600 2125);
FORCEPROP 2 LAST VALUE CONN3_210-HP1-030BR1
J 0
(-16600 2075);
DISPLAY 0.723404 (-16600 2075);
PAINT AQUA (-16600 2075);
FORCEPROP 1 LAST LOCATION JP4003
J 0
(-16600 2025);
DISPLAY 0.723404 (-16600 2025);
PAINT AQUA (-16600 2025);
FORCEPROP 0 LASTPIN (-16750 1850) $PN 1
J 2
(-16760 1860);
DISPLAY 0.680851 (-16760 1860);
PAINT MONO (-16760 1860);
FORCEPROP 0 LASTPIN (-16750 1800) $PN 2
J 2
(-16760 1810);
DISPLAY 0.680851 (-16760 1810);
PAINT MONO (-16760 1810);
FORCEPROP 0 LASTPIN (-16750 1750) $PN 3
J 2
(-16760 1760);
DISPLAY 0.680851 (-16760 1760);
PAINT MONO (-16760 1760);
FORCEPROP 2 LAST CDS_LIB pure_quanta
J 0
(-16550 1800);
DISPLAY INVISIBLE (-16550 1800);
FORCEPROP 1 LAST CDS_LMAN_SYM_OUTLINE -50,100,50,-100
J 0
(-16550 1800);
DISPLAY 0.468085 (-16550 1800);
PAINT GREEN (-16550 1800);
DISPLAY INVISIBLE (-16550 1800);
FORCEPROP 1 LAST NEEDS_NO_SIZE TRUE
J 0
(-16550 1800);
DISPLAY 0.723404 (-16550 1800);
PAINT GREEN (-16550 1800);
DISPLAY INVISIBLE (-16550 1800);
FORCEPROP 1 LAST PATH I12
J 0
(-16550 1800);
DISPLAY 0.723404 (-16550 1800);
PAINT GREEN (-16550 1800);
DISPLAY INVISIBLE (-16550 1800);
FORCEPROP 0 LAST $SEC 1
J 0
(-16600 2175);
DISPLAY 0.680851 (-16600 2175);
PAINT MONO (-16600 2175);
DISPLAY INVISIBLE (-16600 2175);
FORCEPROP 0 LAST CDS_SEC 1
J 0
(-16600 2175);
DISPLAY 1.021277 (-16600 2175);
DISPLAY INVISIBLE (-16600 2175);
FORCEADD OFFPAGE..5
(-17525 3200);
FORCEPROP 2 LAST $XR3 215 
J 0
(-17900 3164);
DISPLAY 0.638298 (-17900 3164);
PAINT MONO (-17900 3164);
FORCEPROP 2 LAST $XR2 183 
J 0
(-17780 3164);
DISPLAY 0.638298 (-17780 3164);
PAINT MONO (-17780 3164);
FORCEPROP 2 LAST $XR1 305 
J 0
(-17900 3200);
DISPLAY 0.638298 (-17900 3200);
PAINT MONO (-17900 3200);
FORCEPROP 2 LAST $XR0 228 
J 0
(-17780 3200);
DISPLAY 0.638298 (-17780 3200);
PAINT MONO (-17780 3200);
FORCEPROP 1 LAST COMMENT_BODY TRUE
J 0
(-17425 3125);
DISPLAY 1.170213 (-17425 3125);
PAINT GREEN (-17425 3125);
DISPLAY INVISIBLE (-17425 3125);
FORCEPROP 1 LAST OFFPAGE TRUE
J 0
(-17200 3075);
DISPLAY 0.872340 (-17200 3075);
PAINT AQUA (-17200 3075);
DISPLAY INVISIBLE (-17200 3075);
FORCEPROP 2 LAST CDS_LIB standard
J 2
(-17525 3200);
DISPLAY INVISIBLE (-17525 3200);
FORCEPROP 2 LAST PATH I13
J 0
(-17775 3250);
DISPLAY 1.021277 (-17775 3250);
DISPLAY INVISIBLE (-17775 3250);
FORCEADD Q_CAP..1
(-17150 4325);
FORCEPROP 1 LAST PART_NUMBER CH5104KEB02
J 0
(-17075 4275);
DISPLAY 0.723404 (-17075 4275);
PAINT WHITE (-17075 4275);
DISPLAY INVISIBLE (-17075 4275);
FORCEPROP 1 LAST MATERIAL X6S
J 0
(-17075 4325);
DISPLAY 0.723404 (-17075 4325);
PAINT SKYBLUE (-17075 4325);
FORCEPROP 1 LAST PACK_TYPE C0402
J 0
(-17075 4225);
DISPLAY 0.723404 (-17075 4225);
PAINT SKYBLUE (-17075 4225);
FORCEPROP 2 LAST ROOM HSC1_BOM1
J 0
(-17075 4525);
DISPLAY 1.021277 (-17075 4525);
FORCEPROP 1 LAST VOLTAGE 25V
J 0
(-17075 4375);
DISPLAY 0.723404 (-17075 4375);
PAINT SKYBLUE (-17075 4375);
FORCEPROP 1 LAST VALUE 1UF
J 0
(-17075 4425);
DISPLAY 0.723404 (-17075 4425);
PAINT SKYBLUE (-17075 4425);
FORCEPROP 1 LAST LOCATION PC2186
J 0
(-17075 4475);
DISPLAY 0.723404 (-17075 4475);
PAINT AQUA (-17075 4475);
FORCEPROP 1 LASTPIN (-17150 4425) $PN 1
J 0
(-17140 4405);
DISPLAY 0.787234 (-17140 4405);
PAINT MONO (-17140 4405);
FORCEPROP 1 LASTPIN (-17150 4225) $PN 2
J 0
(-17140 4205);
DISPLAY 0.787234 (-17140 4205);
PAINT MONO (-17140 4205);
FORCEPROP 1 LAST TOLERANCE 10%
J 0
(-17100 4275);
DISPLAY 0.978723 (-17100 4275);
PAINT SKYBLUE (-17100 4275);
DISPLAY INVISIBLE (-17100 4275);
FORCEPROP 2 LAST CDS_LIB pure_quanta
J 0
(-17150 4325);
DISPLAY INVISIBLE (-17150 4325);
FORCEPROP 1 LAST PATH I14
J 0
(-17100 4475);
DISPLAY 0.978723 (-17100 4475);
PAINT WHITE (-17100 4475);
DISPLAY INVISIBLE (-17100 4475);
FORCEPROP 0 LAST $SEC 1
J 0
(-17075 4525);
DISPLAY 0.680851 (-17075 4525);
PAINT MONO (-17075 4525);
DISPLAY INVISIBLE (-17075 4525);
FORCEPROP 0 LAST CDS_SEC 1
J 0
(-17075 4525);
DISPLAY 1.021277 (-17075 4525);
DISPLAY INVISIBLE (-17075 4525);
FORCEADD OFFPAGE..3
R 2
(-16825 3775);
FORCEPROP 2 LAST $XR1 305 
J 0
(-17225 3775);
DISPLAY 0.638298 (-17225 3775);
PAINT MONO (-17225 3775);
FORCEPROP 2 LAST $XR0 241 
J 0
(-17105 3775);
DISPLAY 0.638298 (-17105 3775);
PAINT MONO (-17105 3775);
FORCEPROP 1 LAST COMMENT_BODY TRUE
J 2
(-16775 3675);
DISPLAY 0.872340 (-16775 3675);
PAINT GREEN (-16775 3675);
DISPLAY INVISIBLE (-16775 3675);
FORCEPROP 1 LAST OFFPAGE TRUE
J 2
(-17150 3650);
DISPLAY 0.872340 (-17150 3650);
PAINT GREEN (-17150 3650);
DISPLAY INVISIBLE (-17150 3650);
FORCEPROP 2 LAST CDS_LIB standard
J 2
(-16825 3775);
DISPLAY INVISIBLE (-16825 3775);
FORCEPROP 2 LAST PATH I15
J 0
(-17100 3825);
DISPLAY 1.021277 (-17100 3825);
DISPLAY INVISIBLE (-17100 3825);
FORCEADD Q_RES..1
(-16350 3200);
FORCEPROP 1 LAST PART_NUMBER CS00002JB13
J 0
(-16700 3150);
DISPLAY 0.723404 (-16700 3150);
PAINT WHITE (-16700 3150);
DISPLAY INVISIBLE (-16700 3150);
FORCEPROP 1 LAST WATTAGE 1/16W
J 2
(-15975 3225);
DISPLAY 0.723404 (-15975 3225);
PAINT SKYBLUE (-15975 3225);
FORCEPROP 1 LAST VALUE 0
J 2
(-16225 3225);
DISPLAY 0.723404 (-16225 3225);
PAINT SKYBLUE (-16225 3225);
FORCEPROP 1 LAST TOLERANCE 5%
J 0
(-16275 3150);
DISPLAY 0.723404 (-16275 3150);
PAINT SKYBLUE (-16275 3150);
FORCEPROP 1 LAST PACK_TYPE 0402LF
J 0
(-16150 3150);
DISPLAY 0.723404 (-16150 3150);
PAINT SKYBLUE (-16150 3150);
FORCEPROP 1 LAST MATERIAL CHIP
J 0
(-15925 3150);
DISPLAY 0.723404 (-15925 3150);
PAINT SKYBLUE (-15925 3150);
FORCEPROP 1 LAST $LOCATION R3924
J 0
(-16700 3200);
DISPLAY 0.723404 (-16700 3200);
PAINT AQUA (-16700 3200);
FORCEPROP 1 LASTPIN (-16450 3200) $PN 1
J 0
(-16438 3212);
DISPLAY 0.787234 (-16438 3212);
PAINT MONO (-16438 3212);
FORCEPROP 1 LASTPIN (-16250 3200) $PN 2
J 0
(-16288 3212);
DISPLAY 0.787234 (-16288 3212);
PAINT MONO (-16288 3212);
FORCEPROP 2 LAST CDS_LIB pure_quanta
J 0
(-16350 3200);
DISPLAY INVISIBLE (-16350 3200);
FORCEPROP 1 LAST PATH I17
J 0
(-16400 3350);
DISPLAY 0.978723 (-16400 3350);
PAINT WHITE (-16400 3350);
DISPLAY INVISIBLE (-16400 3350);
FORCEPROP 0 LAST CDS_LOCATION R3924
J 0
(-15975 3275);
DISPLAY 1.021277 (-15975 3275);
DISPLAY INVISIBLE (-15975 3275);
FORCEPROP 0 LAST $SEC 1
J 0
(-15975 3275);
DISPLAY 0.680851 (-15975 3275);
PAINT MONO (-15975 3275);
DISPLAY INVISIBLE (-15975 3275);
FORCEPROP 0 LAST CDS_SEC 1
J 0
(-15975 3275);
DISPLAY 1.021277 (-15975 3275);
DISPLAY INVISIBLE (-15975 3275);
FORCEADD OFFPAGE..5
(-16025 2850);
FORCEPROP 2 LAST $XR1 303 
J 0
(-16430 2850);
DISPLAY 0.638298 (-16430 2850);
PAINT MONO (-16430 2850);
FORCEPROP 2 LAST $XR0 302 
J 0
(-16310 2850);
DISPLAY 0.638298 (-16310 2850);
PAINT MONO (-16310 2850);
FORCEPROP 1 LAST COMMENT_BODY TRUE
J 0
(-15925 2775);
DISPLAY 1.170213 (-15925 2775);
PAINT GREEN (-15925 2775);
DISPLAY INVISIBLE (-15925 2775);
FORCEPROP 1 LAST OFFPAGE TRUE
J 0
(-15700 2725);
DISPLAY 0.872340 (-15700 2725);
PAINT AQUA (-15700 2725);
DISPLAY INVISIBLE (-15700 2725);
FORCEPROP 2 LAST CDS_LIB standard
J 0
(-16025 2850);
DISPLAY INVISIBLE (-16025 2850);
FORCEPROP 2 LAST PATH I18
J 0
(-16300 2900);
DISPLAY 1.021277 (-16300 2900);
DISPLAY INVISIBLE (-16300 2900);
FORCEADD OFFPAGE..4
R 2
(-16025 3000);
FORCEPROP 2 LAST $XR1 305 
J 0
(-16397 3000);
DISPLAY 0.638298 (-16397 3000);
PAINT MONO (-16397 3000);
FORCEPROP 2 LAST $XR0 301 
J 0
(-16277 3000);
DISPLAY 0.638298 (-16277 3000);
PAINT MONO (-16277 3000);
FORCEPROP 1 LAST COMMENT_BODY TRUE
J 2
(-16000 2900);
DISPLAY 0.872340 (-16000 2900);
PAINT GREEN (-16000 2900);
DISPLAY INVISIBLE (-16000 2900);
FORCEPROP 1 LAST OFFPAGE TRUE
J 2
(-16350 2875);
DISPLAY 0.872340 (-16350 2875);
PAINT GREEN (-16350 2875);
DISPLAY INVISIBLE (-16350 2875);
FORCEPROP 2 LAST CDS_LIB standard
J 0
(-16025 3000);
DISPLAY INVISIBLE (-16025 3000);
FORCEPROP 2 LAST PATH I19
J 0
(-16275 3050);
DISPLAY 1.021277 (-16275 3050);
DISPLAY INVISIBLE (-16275 3050);
FORCEADD OFFPAGE..4
R 2
(-17400 625);
FORCEPROP 2 LAST $XR0 245 
J 0
(-17652 625);
DISPLAY 0.638298 (-17652 625);
PAINT MONO (-17652 625);
FORCEPROP 1 LAST COMMENT_BODY TRUE
J 2
(-17375 525);
DISPLAY 0.872340 (-17375 525);
PAINT GREEN (-17375 525);
DISPLAY INVISIBLE (-17375 525);
FORCEPROP 1 LAST OFFPAGE TRUE
J 2
(-17725 500);
DISPLAY 0.872340 (-17725 500);
PAINT GREEN (-17725 500);
DISPLAY INVISIBLE (-17725 500);
FORCEPROP 2 LAST CDS_LIB standard
J 0
(-17400 625);
DISPLAY INVISIBLE (-17400 625);
FORCEPROP 2 LAST PATH I2
J 0
(-17650 675);
DISPLAY 1.021277 (-17650 675);
DISPLAY INVISIBLE (-17650 675);
FORCEADD OFFPAGE..4
R 2
(-16825 3875);
FORCEPROP 2 LAST $XR1 305 
J 0
(-17197 3875);
DISPLAY 0.638298 (-17197 3875);
PAINT MONO (-17197 3875);
FORCEPROP 2 LAST $XR0 241 
J 0
(-17077 3875);
DISPLAY 0.638298 (-17077 3875);
PAINT MONO (-17077 3875);
FORCEPROP 1 LAST COMMENT_BODY TRUE
J 2
(-16800 3775);
DISPLAY 0.872340 (-16800 3775);
PAINT GREEN (-16800 3775);
DISPLAY INVISIBLE (-16800 3775);
FORCEPROP 1 LAST OFFPAGE TRUE
J 2
(-17150 3750);
DISPLAY 0.872340 (-17150 3750);
PAINT GREEN (-17150 3750);
DISPLAY INVISIBLE (-17150 3750);
FORCEPROP 2 LAST CDS_LIB standard
J 0
(-16825 3875);
DISPLAY INVISIBLE (-16825 3875);
FORCEPROP 2 LAST PATH I21
J 0
(-17075 3925);
DISPLAY 1.021277 (-17075 3925);
DISPLAY INVISIBLE (-17075 3925);
FORCEADD UNIVERSAL_GND..1
(-16650 4050);
FORCEPROP 3 LASTPIN (-16650 4100) SIG_NAME AGND_HSC\g
J 0
(-16640 4110);
DISPLAY 0.659574 (-16640 4110);
PAINT MONO (-16640 4110);
DISPLAY INVISIBLE (-16640 4110);
FORCEPROP 1 LAST HDL_POWER AGND_HSC
J 1
(-16625 3975);
DISPLAY 0.723404 (-16625 3975);
PAINT GREEN (-16625 3975);
FORCEPROP 2 LAST CDS_LIB logical_power
J 0
(-16650 4050);
DISPLAY INVISIBLE (-16650 4050);
FORCEPROP 1 LAST PATH I22
J 0
(-16575 4050);
DISPLAY 0.872340 (-16575 4050);
PAINT AQUA (-16575 4050);
DISPLAY INVISIBLE (-16575 4050);
FORCEADD Q_CAP..1
(-16650 4300);
FORCEPROP 1 LAST PART_NUMBER CH5104KEB02
J 0
(-16575 4275);
DISPLAY 0.723404 (-16575 4275);
PAINT WHITE (-16575 4275);
DISPLAY INVISIBLE (-16575 4275);
FORCEPROP 1 LAST VALUE 1UF
J 0
(-16575 4425);
DISPLAY 0.723404 (-16575 4425);
PAINT SKYBLUE (-16575 4425);
FORCEPROP 1 LAST PACK_TYPE C0402
J 0
(-16575 4225);
DISPLAY 0.723404 (-16575 4225);
PAINT SKYBLUE (-16575 4225);
FORCEPROP 1 LAST MATERIAL X6S
J 0
(-16575 4325);
DISPLAY 0.723404 (-16575 4325);
PAINT SKYBLUE (-16575 4325);
FORCEPROP 1 LAST VOLTAGE 25V
J 0
(-16575 4375);
DISPLAY 0.723404 (-16575 4375);
PAINT SKYBLUE (-16575 4375);
FORCEPROP 2 LAST ROOM HSC1_BOM1
J 0
(-16575 4525);
DISPLAY 1.021277 (-16575 4525);
FORCEPROP 1 LAST LOCATION PC2187
J 0
(-16575 4475);
DISPLAY 0.723404 (-16575 4475);
PAINT AQUA (-16575 4475);
FORCEPROP 1 LASTPIN (-16650 4400) $PN 1
J 0
(-16640 4380);
DISPLAY 0.787234 (-16640 4380);
PAINT MONO (-16640 4380);
FORCEPROP 1 LASTPIN (-16650 4200) $PN 2
J 0
(-16640 4180);
DISPLAY 0.787234 (-16640 4180);
PAINT MONO (-16640 4180);
FORCEPROP 2 LAST CDS_LIB pure_quanta
J 0
(-16650 4300);
DISPLAY INVISIBLE (-16650 4300);
FORCEPROP 1 LAST TOLERANCE 10%
J 0
(-16600 4250);
DISPLAY 0.978723 (-16600 4250);
PAINT SKYBLUE (-16600 4250);
DISPLAY INVISIBLE (-16600 4250);
FORCEPROP 1 LAST PATH I23
J 0
(-16600 4450);
DISPLAY 0.978723 (-16600 4450);
PAINT WHITE (-16600 4450);
DISPLAY INVISIBLE (-16600 4450);
FORCEPROP 0 LAST $SEC 1
J 0
(-16575 4525);
DISPLAY 0.680851 (-16575 4525);
PAINT MONO (-16575 4525);
DISPLAY INVISIBLE (-16575 4525);
FORCEPROP 0 LAST CDS_SEC 1
J 0
(-16575 4525);
DISPLAY 1.021277 (-16575 4525);
DISPLAY INVISIBLE (-16575 4525);
FORCEADD Q_RES..1
R 1
(-16950 4750);
FORCEPROP 1 LAST PART_NUMBER CS00002JB13
J 0
(-16875 4650);
DISPLAY 0.723404 (-16875 4650);
PAINT WHITE (-16875 4650);
DISPLAY INVISIBLE (-16875 4650);
FORCEPROP 2 LAST ROOM HSC1_BOM1
J 0
(-16875 4950);
DISPLAY 1.021277 (-16875 4950);
FORCEPROP 1 LAST MATERIAL CHIP
J 0
(-16875 4600);
DISPLAY 0.787234 (-16875 4600);
PAINT SKYBLUE (-16875 4600);
FORCEPROP 1 LAST TOLERANCE 5%
J 0
(-16875 4800);
DISPLAY 0.723404 (-16875 4800);
PAINT SKYBLUE (-16875 4800);
FORCEPROP 1 LAST VALUE 0
R 2
J 0
(-16850 4875);
DISPLAY 0.723404 (-16850 4875);
PAINT SKYBLUE (-16850 4875);
FORCEPROP 1 LAST PACK_TYPE 0402LF
J 0
(-16875 4750);
DISPLAY 0.723404 (-16875 4750);
PAINT SKYBLUE (-16875 4750);
FORCEPROP 1 LAST WATTAGE 1/16W
J 0
(-16875 4700);
DISPLAY 0.723404 (-16875 4700);
PAINT SKYBLUE (-16875 4700);
FORCEPROP 1 LAST LOCATION PR2149
J 0
(-16875 4900);
DISPLAY 0.723404 (-16875 4900);
PAINT AQUA (-16875 4900);
FORCEPROP 1 LASTPIN (-16950 4650) $PN 1
R 1
J 0
(-16962 4662);
DISPLAY 0.787234 (-16962 4662);
PAINT MONO (-16962 4662);
FORCEPROP 1 LASTPIN (-16950 4850) $PN 2
R 1
J 0
(-16962 4812);
DISPLAY 0.787234 (-16962 4812);
PAINT MONO (-16962 4812);
FORCEPROP 2 LAST CDS_LIB pure_quanta
J 0
(-16950 4750);
DISPLAY INVISIBLE (-16950 4750);
FORCEPROP 1 LAST PATH I24
R 1
J 0
(-17100 4700);
DISPLAY 0.978723 (-17100 4700);
PAINT WHITE (-17100 4700);
DISPLAY INVISIBLE (-17100 4700);
FORCEPROP 0 LAST $SEC 1
R 1
J 0
(-16875 4950);
DISPLAY 0.680851 (-16875 4950);
PAINT MONO (-16875 4950);
DISPLAY INVISIBLE (-16875 4950);
FORCEPROP 0 LAST CDS_SEC 1
R 1
J 0
(-16875 4950);
DISPLAY 1.021277 (-16875 4950);
DISPLAY INVISIBLE (-16875 4950);
FORCEADD Q_RES..1
(-15400 1350);
FORCEPROP 1 LAST PART_NUMBER CS38202FB01
J 0
(-15550 1225);
DISPLAY 0.723404 (-15550 1225);
PAINT WHITE (-15550 1225);
DISPLAY INVISIBLE (-15550 1225);
FORCEPROP 1 LAST PACK_TYPE 0402LF
J 0
(-15300 1275);
DISPLAY 0.723404 (-15300 1275);
PAINT SKYBLUE (-15300 1275);
FORCEPROP 1 LAST TOLERANCE 1%
J 0
(-15300 1375);
DISPLAY 0.723404 (-15300 1375);
PAINT SKYBLUE (-15300 1375);
FORCEPROP 1 LAST VALUE 82K
J 2
(-15350 1375);
DISPLAY 0.723404 (-15350 1375);
PAINT SKYBLUE (-15350 1375);
FORCEPROP 1 LAST MATERIAL CHIP
J 0
(-15475 1275);
DISPLAY 0.723404 (-15475 1275);
PAINT SKYBLUE (-15475 1275);
FORCEPROP 1 LAST WATTAGE 1/16W
J 2
(-15500 1275);
DISPLAY 0.723404 (-15500 1275);
PAINT SKYBLUE (-15500 1275);
FORCEPROP 1 LAST LOCATION R4901
J 0
(-15650 1375);
DISPLAY 0.723404 (-15650 1375);
PAINT AQUA (-15650 1375);
FORCEPROP 1 LASTPIN (-15500 1350) $PN 1
J 0
(-15488 1362);
DISPLAY 0.787234 (-15488 1362);
PAINT MONO (-15488 1362);
FORCEPROP 1 LASTPIN (-15300 1350) $PN 2
J 0
(-15338 1362);
DISPLAY 0.787234 (-15338 1362);
PAINT MONO (-15338 1362);
FORCEPROP 2 LAST CDS_LIB pure_quanta
J 0
(-15400 1350);
DISPLAY INVISIBLE (-15400 1350);
FORCEPROP 1 LAST PATH I26
J 0
(-15450 1500);
DISPLAY 0.978723 (-15450 1500);
PAINT WHITE (-15450 1500);
DISPLAY INVISIBLE (-15450 1500);
FORCEPROP 0 LAST $SEC 1
J 0
(-15300 1425);
DISPLAY 0.680851 (-15300 1425);
PAINT MONO (-15300 1425);
DISPLAY INVISIBLE (-15300 1425);
FORCEPROP 0 LAST CDS_SEC 1
J 0
(-15300 1425);
DISPLAY 1.021277 (-15300 1425);
DISPLAY INVISIBLE (-15300 1425);
FORCEADD OFFPAGE..4
(-15150 1575);
FORCEPROP 2 LAST $XR0 304 
J 0
(-14964 1575);
DISPLAY 0.638298 (-14964 1575);
PAINT MONO (-14964 1575);
FORCEPROP 1 LAST COMMENT_BODY TRUE
J 0
(-15175 1475);
DISPLAY 0.872340 (-15175 1475);
PAINT GREEN (-15175 1475);
DISPLAY INVISIBLE (-15175 1475);
FORCEPROP 1 LAST OFFPAGE TRUE
J 0
(-14825 1450);
DISPLAY 0.872340 (-14825 1450);
PAINT GREEN (-14825 1450);
DISPLAY INVISIBLE (-14825 1450);
FORCEPROP 2 LAST CDS_LIB standard
J 2
(-15150 1575);
DISPLAY INVISIBLE (-15150 1575);
FORCEPROP 2 LAST PATH I27
J 0
(-14950 1625);
DISPLAY 1.021277 (-14950 1625);
DISPLAY INVISIBLE (-14950 1625);
FORCEADD UNIVERSAL_GND..1
(-15050 2575);
FORCEPROP 3 LASTPIN (-15050 2625) SIG_NAME AGND_HSC\g
J 0
(-15040 2635);
DISPLAY 0.659574 (-15040 2635);
PAINT MONO (-15040 2635);
DISPLAY INVISIBLE (-15040 2635);
FORCEPROP 1 LAST HDL_POWER AGND_HSC
J 1
(-15025 2500);
DISPLAY 0.723404 (-15025 2500);
PAINT GREEN (-15025 2500);
FORCEPROP 2 LAST CDS_LIB logical_power
J 0
(-15050 2575);
DISPLAY INVISIBLE (-15050 2575);
FORCEPROP 1 LAST PATH I28
J 0
(-14975 2575);
DISPLAY 0.872340 (-14975 2575);
PAINT AQUA (-14975 2575);
DISPLAY INVISIBLE (-14975 2575);
FORCEADD Q_CAP..1
(-14475 850);
FORCEPROP 1 LAST PART_NUMBER CH4106K1B01
J 0
(-14425 725);
DISPLAY 0.723404 (-14425 725);
PAINT WHITE (-14425 725);
DISPLAY INVISIBLE (-14425 725);
FORCEPROP 1 LAST VALUE 100NF
J 0
(-14425 925);
DISPLAY 0.723404 (-14425 925);
PAINT SKYBLUE (-14425 925);
FORCEPROP 1 LAST TOLERANCE 10%
J 0
(-14425 825);
DISPLAY 0.723404 (-14425 825);
PAINT SKYBLUE (-14425 825);
FORCEPROP 1 LAST MATERIAL X7R
J 0
(-14425 775);
DISPLAY 0.723404 (-14425 775);
PAINT SKYBLUE (-14425 775);
FORCEPROP 1 LAST PACK_TYPE C0402
J 0
(-14425 675);
DISPLAY 0.723404 (-14425 675);
PAINT SKYBLUE (-14425 675);
FORCEPROP 1 LAST VOLTAGE 50V
J 0
(-14425 875);
DISPLAY 0.723404 (-14425 875);
PAINT SKYBLUE (-14425 875);
FORCEPROP 1 LAST LOCATION C2179
J 0
(-14425 975);
DISPLAY 0.723404 (-14425 975);
PAINT AQUA (-14425 975);
FORCEPROP 2 LAST CDS_LIB pure_quanta
J 0
(-14475 850);
DISPLAY INVISIBLE (-14475 850);
FORCEPROP 1 LAST PATH I29
J 0
(-14425 1000);
DISPLAY 0.978723 (-14425 1000);
PAINT WHITE (-14425 1000);
DISPLAY INVISIBLE (-14425 1000);
FORCEPROP 0 LAST $SEC 1
J 0
(-14425 1000);
DISPLAY INVISIBLE (-14425 1000);
FORCEPROP 0 LAST CDS_SEC 1
J 0
(-14425 1000);
DISPLAY INVISIBLE (-14425 1000);
FORCEPROP 1 LASTPIN (-14475 950) $PN 1
J 0
(-14465 930);
DISPLAY 0.787234 (-14465 930);
PAINT MONO (-14465 930);
DISPLAY INVISIBLE (-14465 930);
FORCEPROP 1 LASTPIN (-14475 750) $PN 2
J 0
(-14465 730);
DISPLAY 0.787234 (-14465 730);
PAINT MONO (-14465 730);
DISPLAY INVISIBLE (-14465 730);
FORCEADD Q_CAP..1
(-17225 400);
FORCEPROP 1 LAST PART_NUMBER CH4104K1B00
J 0
(-17150 450);
DISPLAY 0.723404 (-17150 450);
PAINT BLUE (-17150 450);
DISPLAY INVISIBLE (-17150 450);
FORCEPROP 1 LAST TOLERANCE 10%
J 0
(-17150 300);
DISPLAY 0.723404 (-17150 300);
PAINT SKYBLUE (-17150 300);
FORCEPROP 1 LAST MATERIAL X7R
J 0
(-17150 250);
DISPLAY 0.723404 (-17150 250);
PAINT SKYBLUE (-17150 250);
FORCEPROP 1 LAST PACK_TYPE 0402
J 0
(-17150 200);
DISPLAY 0.723404 (-17150 200);
PAINT SKYBLUE (-17150 200);
FORCEPROP 1 LAST VOLTAGE 25V
J 0
(-17150 350);
DISPLAY 0.723404 (-17150 350);
PAINT SKYBLUE (-17150 350);
FORCEPROP 1 LAST VALUE 0.1UF
J 0
(-17150 400);
DISPLAY 0.723404 (-17150 400);
PAINT SKYBLUE (-17150 400);
FORCEPROP 1 LAST LOCATION C1797
J 0
(-17150 500);
DISPLAY 0.978723 (-17150 500);
FORCEPROP 2 LAST CDS_LIB pure_quanta
J 0
(-17225 400);
DISPLAY INVISIBLE (-17225 400);
FORCEPROP 1 LAST PATH I3
J 0
(-17175 550);
DISPLAY 0.978723 (-17175 550);
PAINT WHITE (-17175 550);
DISPLAY INVISIBLE (-17175 550);
FORCEPROP 0 LAST $SEC 1
J 0
(-17175 550);
DISPLAY 0.680851 (-17175 550);
PAINT MONO (-17175 550);
DISPLAY INVISIBLE (-17175 550);
FORCEPROP 0 LAST CDS_SEC 1
J 0
(-17175 550);
DISPLAY 1.021277 (-17175 550);
DISPLAY INVISIBLE (-17175 550);
FORCEPROP 1 LASTPIN (-17225 500) $PN 1
J 0
(-17215 480);
DISPLAY 0.787234 (-17215 480);
PAINT MONO (-17215 480);
DISPLAY INVISIBLE (-17215 480);
FORCEPROP 1 LASTPIN (-17225 300) $PN 2
J 0
(-17215 280);
DISPLAY 0.787234 (-17215 280);
PAINT MONO (-17215 280);
DISPLAY INVISIBLE (-17215 280);
FORCEADD OFFPAGE..5
R 2
(-14325 1350);
FORCEPROP 2 LAST $XR1 305 
J 0
(-14016 1350);
DISPLAY 0.638298 (-14016 1350);
PAINT MONO (-14016 1350);
FORCEPROP 2 LAST $XR0 301 
J 0
(-14136 1350);
DISPLAY 0.638298 (-14136 1350);
PAINT MONO (-14136 1350);
FORCEPROP 1 LAST COMMENT_BODY TRUE
J 2
(-14425 1275);
DISPLAY 1.170213 (-14425 1275);
PAINT GREEN (-14425 1275);
DISPLAY INVISIBLE (-14425 1275);
FORCEPROP 1 LAST OFFPAGE TRUE
J 2
(-14650 1225);
DISPLAY 0.872340 (-14650 1225);
PAINT AQUA (-14650 1225);
DISPLAY INVISIBLE (-14650 1225);
FORCEPROP 2 LAST CDS_LIB standard
J 2
(-14325 1350);
DISPLAY INVISIBLE (-14325 1350);
FORCEPROP 2 LAST PATH I30
J 0
(-14125 1400);
DISPLAY 1.021277 (-14125 1400);
DISPLAY INVISIBLE (-14125 1400);
FORCEADD UNIVERSAL_GND..1
(-14575 2250);
FORCEPROP 3 LASTPIN (-14575 2300) SIG_NAME AGND_HSC\g
J 0
(-14565 2310);
DISPLAY 0.659574 (-14565 2310);
PAINT MONO (-14565 2310);
DISPLAY INVISIBLE (-14565 2310);
FORCEPROP 1 LAST HDL_POWER AGND_HSC
J 1
(-14575 2175);
DISPLAY 0.723404 (-14575 2175);
PAINT GREEN (-14575 2175);
FORCEPROP 2 LAST CDS_LIB logical_power
J 0
(-14575 2250);
DISPLAY INVISIBLE (-14575 2250);
FORCEPROP 1 LAST PATH I31
J 0
(-14500 2250);
DISPLAY 0.872340 (-14500 2250);
PAINT AQUA (-14500 2250);
DISPLAY INVISIBLE (-14500 2250);
FORCEADD Q_RES..1
R 1
(-14575 2450);
FORCEPROP 1 LAST PART_NUMBER CS00002JB13
J 0
(-14500 2325);
DISPLAY 0.723404 (-14500 2325);
PAINT WHITE (-14500 2325);
DISPLAY INVISIBLE (-14500 2325);
FORCEPROP 2 LAST ROOM HSC1_BOM1
J 0
(-14500 2625);
DISPLAY 1.021277 (-14500 2625);
FORCEPROP 1 LAST TOLERANCE 5%
J 0
(-14500 2475);
DISPLAY 0.723404 (-14500 2475);
PAINT SKYBLUE (-14500 2475);
FORCEPROP 1 LAST PACK_TYPE 0402LF
J 0
(-14500 2425);
DISPLAY 0.723404 (-14500 2425);
PAINT SKYBLUE (-14500 2425);
FORCEPROP 1 LAST VALUE 0
J 0
(-14500 2525);
DISPLAY 0.723404 (-14500 2525);
PAINT SKYBLUE (-14500 2525);
FORCEPROP 1 LAST MATERIAL CHIP
J 0
(-14500 2275);
DISPLAY 0.808511 (-14500 2275);
PAINT SKYBLUE (-14500 2275);
FORCEPROP 1 LAST WATTAGE 1/16W
J 0
(-14500 2375);
DISPLAY 0.723404 (-14500 2375);
PAINT SKYBLUE (-14500 2375);
FORCEPROP 1 LAST LOCATION PR3930
J 0
(-14500 2575);
DISPLAY 0.723404 (-14500 2575);
PAINT AQUA (-14500 2575);
FORCEPROP 1 LASTPIN (-14575 2350) $PN 1
R 1
J 0
(-14587 2362);
DISPLAY 0.787234 (-14587 2362);
PAINT MONO (-14587 2362);
FORCEPROP 1 LASTPIN (-14575 2550) $PN 2
R 1
J 0
(-14587 2512);
DISPLAY 0.787234 (-14587 2512);
PAINT MONO (-14587 2512);
FORCEPROP 2 LAST CDS_LIB pure_quanta
J 0
(-14575 2450);
DISPLAY INVISIBLE (-14575 2450);
FORCEPROP 1 LAST PATH I32
R 1
J 0
(-14725 2400);
DISPLAY 0.978723 (-14725 2400);
PAINT WHITE (-14725 2400);
DISPLAY INVISIBLE (-14725 2400);
FORCEPROP 0 LAST $SEC 1
R 1
J 0
(-14500 2625);
DISPLAY 0.680851 (-14500 2625);
PAINT MONO (-14500 2625);
DISPLAY INVISIBLE (-14500 2625);
FORCEPROP 0 LAST CDS_SEC 1
R 1
J 0
(-14500 2625);
DISPLAY 1.021277 (-14500 2625);
DISPLAY INVISIBLE (-14500 2625);
FORCEADD Q_RES..1
R 1
(-15950 3375);
FORCEPROP 1 LAST PART_NUMBER CS21002FB06
J 0
(-15875 3275);
DISPLAY 0.723404 (-15875 3275);
PAINT WHITE (-15875 3275);
DISPLAY INVISIBLE (-15875 3275);
FORCEPROP 1 LAST VALUE 1K
J 0
(-15875 3475);
DISPLAY 0.723404 (-15875 3475);
PAINT SKYBLUE (-15875 3475);
FORCEPROP 1 LAST TOLERANCE 1%
J 0
(-15875 3425);
DISPLAY 0.723404 (-15875 3425);
PAINT SKYBLUE (-15875 3425);
FORCEPROP 1 LAST WATTAGE 1/16W
J 0
(-15875 3325);
DISPLAY 0.723404 (-15875 3325);
PAINT SKYBLUE (-15875 3325);
FORCEPROP 1 LAST PACK_TYPE 0402LF
J 0
(-15875 3375);
DISPLAY 0.723404 (-15875 3375);
PAINT SKYBLUE (-15875 3375);
FORCEPROP 1 LAST MATERIAL CHIP
J 0
(-15875 3225);
DISPLAY 0.638298 (-15875 3225);
PAINT SKYBLUE (-15875 3225);
FORCEPROP 1 LAST $LOCATION R3925
J 0
(-15875 3525);
DISPLAY 0.723404 (-15875 3525);
PAINT AQUA (-15875 3525);
FORCEPROP 1 LASTPIN (-15950 3275) $PN 1
R 1
J 0
(-15962 3287);
DISPLAY 0.787234 (-15962 3287);
PAINT MONO (-15962 3287);
FORCEPROP 1 LASTPIN (-15950 3475) $PN 2
R 1
J 0
(-15962 3437);
DISPLAY 0.787234 (-15962 3437);
PAINT MONO (-15962 3437);
FORCEPROP 2 LAST CDS_LIB pure_quanta
J 0
(-15950 3375);
DISPLAY INVISIBLE (-15950 3375);
FORCEPROP 1 LAST PATH I33
R 1
J 0
(-16100 3325);
DISPLAY 0.978723 (-16100 3325);
PAINT WHITE (-16100 3325);
DISPLAY INVISIBLE (-16100 3325);
FORCEPROP 0 LAST CDS_LOCATION R3925
R 1
J 0
(-15875 3575);
DISPLAY 1.021277 (-15875 3575);
DISPLAY INVISIBLE (-15875 3575);
FORCEPROP 0 LAST $SEC 1
R 1
J 0
(-15875 3575);
DISPLAY 0.680851 (-15875 3575);
PAINT MONO (-15875 3575);
DISPLAY INVISIBLE (-15875 3575);
FORCEPROP 0 LAST CDS_SEC 1
R 1
J 0
(-15875 3575);
DISPLAY 1.021277 (-15875 3575);
DISPLAY INVISIBLE (-15875 3575);
FORCEADD UNIVERSAL_POWER..1
(-15950 3550);
FORCEPROP 3 LASTPIN (-15950 3500) SIG_NAME P3V3_AUX\g
J 0
(-15940 3510);
DISPLAY 0.659574 (-15940 3510);
PAINT MONO (-15940 3510);
DISPLAY INVISIBLE (-15940 3510);
FORCEPROP 1 LAST HDL_POWER P3V3_AUX
J 1
(-15950 3600);
DISPLAY 0.723404 (-15950 3600);
PAINT GREEN (-15950 3600);
FORCEPROP 2 LAST CDS_LIB logical_power
J 0
(-15950 3550);
DISPLAY INVISIBLE (-15950 3550);
FORCEPROP 1 LAST PATH I34
J 0
(-15900 3575);
DISPLAY 0.872340 (-15900 3575);
PAINT AQUA (-15900 3575);
DISPLAY INVISIBLE (-15900 3575);
FORCEADD Q_CAP..1
(-15050 2875);
FORCEPROP 1 LAST PART_NUMBER CH5104KEB02
J 0
(-15000 2775);
DISPLAY 0.723404 (-15000 2775);
PAINT WHITE (-15000 2775);
DISPLAY INVISIBLE (-15000 2775);
FORCEPROP 2 LAST ROOM HSC1_BOM1
J 0
(-15000 3025);
DISPLAY 1.021277 (-15000 3025);
FORCEPROP 1 LAST VOLTAGE 25V
J 0
(-15000 2875);
DISPLAY 0.723404 (-15000 2875);
PAINT SKYBLUE (-15000 2875);
FORCEPROP 1 LAST MATERIAL X6S
J 0
(-15000 2825);
DISPLAY 0.723404 (-15000 2825);
PAINT SKYBLUE (-15000 2825);
FORCEPROP 1 LAST VALUE 1UF
J 0
(-15000 2925);
DISPLAY 0.723404 (-15000 2925);
PAINT SKYBLUE (-15000 2925);
FORCEPROP 1 LAST PACK_TYPE C0402
J 0
(-15000 2725);
DISPLAY 0.723404 (-15000 2725);
PAINT SKYBLUE (-15000 2725);
FORCEPROP 1 LAST $LOCATION PC2103
J 0
(-15000 2975);
DISPLAY 0.723404 (-15000 2975);
PAINT AQUA (-15000 2975);
FORCEPROP 1 LASTPIN (-15050 2975) $PN 1
J 0
(-15040 2955);
DISPLAY 0.787234 (-15040 2955);
PAINT MONO (-15040 2955);
FORCEPROP 1 LASTPIN (-15050 2775) $PN 2
J 0
(-15040 2755);
DISPLAY 0.787234 (-15040 2755);
PAINT MONO (-15040 2755);
FORCEPROP 1 LAST TOLERANCE 10%
J 0
(-15000 2825);
DISPLAY 0.978723 (-15000 2825);
PAINT SKYBLUE (-15000 2825);
DISPLAY INVISIBLE (-15000 2825);
FORCEPROP 2 LAST CDS_LIB pure_quanta
J 0
(-15050 2875);
DISPLAY INVISIBLE (-15050 2875);
FORCEPROP 1 LAST PATH I35
J 0
(-15000 3025);
DISPLAY 0.978723 (-15000 3025);
PAINT WHITE (-15000 3025);
DISPLAY INVISIBLE (-15000 3025);
FORCEPROP 0 LAST CDS_LOCATION PC2103
J 0
(-15000 3025);
DISPLAY 1.021277 (-15000 3025);
DISPLAY INVISIBLE (-15000 3025);
FORCEPROP 0 LAST $SEC 1
J 0
(-15000 3025);
DISPLAY 0.680851 (-15000 3025);
PAINT MONO (-15000 3025);
DISPLAY INVISIBLE (-15000 3025);
FORCEPROP 0 LAST CDS_SEC 1
J 0
(-15000 3025);
DISPLAY 1.021277 (-15000 3025);
DISPLAY INVISIBLE (-15000 3025);
FORCEADD UNIVERSAL_POWER..1
(-15325 3550);
FORCEPROP 3 LASTPIN (-15325 3500) SIG_NAME HSC_VDD\g
J 0
(-15315 3510);
DISPLAY 0.659574 (-15315 3510);
PAINT MONO (-15315 3510);
DISPLAY INVISIBLE (-15315 3510);
FORCEPROP 1 LAST HDL_POWER HSC_VDD
J 1
(-15325 3600);
DISPLAY 0.723404 (-15325 3600);
PAINT GREEN (-15325 3600);
FORCEPROP 2 LAST BOM_COST MIO_VRD_SB
J 0
(-15325 3650);
DISPLAY 0.617021 (-15325 3650);
PAINT PURPLE (-15325 3650);
DISPLAY INVISIBLE (-15325 3650);
FORCEPROP 2 LAST CDS_LIB logical_power
J 0
(-15325 3550);
DISPLAY INVISIBLE (-15325 3550);
FORCEPROP 1 LAST PATH I36
J 0
(-15275 3575);
DISPLAY 0.872340 (-15275 3575);
PAINT AQUA (-15275 3575);
DISPLAY INVISIBLE (-15275 3575);
FORCEADD Q_RES..1
(-15400 3775);
FORCEPROP 1 LAST PART_NUMBER CS00002JB13
J 0
(-15725 3725);
DISPLAY 0.723404 (-15725 3725);
PAINT WHITE (-15725 3725);
DISPLAY INVISIBLE (-15725 3725);
FORCEPROP 1 LAST TOLERANCE 5%
J 0
(-15325 3725);
DISPLAY 0.723404 (-15325 3725);
PAINT SKYBLUE (-15325 3725);
FORCEPROP 1 LAST PACK_TYPE 0402LF
J 0
(-15200 3725);
DISPLAY 0.723404 (-15200 3725);
PAINT SKYBLUE (-15200 3725);
FORCEPROP 1 LAST MATERIAL CHIP
J 0
(-14975 3725);
DISPLAY 0.723404 (-14975 3725);
PAINT SKYBLUE (-14975 3725);
FORCEPROP 2 LAST ROOM HSC1_BOM1
J 0
(-15000 3825);
DISPLAY 1.021277 (-15000 3825);
FORCEPROP 1 LAST VALUE 0
J 2
(-15250 3775);
DISPLAY 0.723404 (-15250 3775);
PAINT SKYBLUE (-15250 3775);
FORCEPROP 1 LAST WATTAGE 1/16W
J 2
(-15000 3775);
DISPLAY 0.723404 (-15000 3775);
PAINT SKYBLUE (-15000 3775);
FORCEPROP 1 LAST LOCATION R1714
J 0
(-15675 3775);
DISPLAY 0.723404 (-15675 3775);
PAINT AQUA (-15675 3775);
FORCEPROP 2 LAST CDS_LIB pure_quanta
J 0
(-15400 3775);
PAINT MONO (-15400 3775);
DISPLAY INVISIBLE (-15400 3775);
FORCEPROP 1 LAST PATH I37
J 0
(-15450 3925);
DISPLAY 0.978723 (-15450 3925);
PAINT WHITE (-15450 3925);
DISPLAY INVISIBLE (-15450 3925);
FORCEPROP 0 LAST $SEC 1
J 0
(-15500 3850);
DISPLAY INVISIBLE (-15500 3850);
FORCEPROP 0 LAST CDS_SEC 1
J 0
(-15500 3850);
DISPLAY INVISIBLE (-15500 3850);
FORCEPROP 1 LASTPIN (-15500 3775) $PN 1
J 0
(-15488 3787);
DISPLAY 0.787234 (-15488 3787);
DISPLAY INVISIBLE (-15488 3787);
FORCEPROP 1 LASTPIN (-15300 3775) $PN 2
J 0
(-15338 3787);
DISPLAY 0.787234 (-15338 3787);
DISPLAY INVISIBLE (-15338 3787);
FORCEADD Q_RES..1
(-15400 3875);
FORCEPROP 1 LAST PART_NUMBER CS03322FB03
J 0
(-15500 3950);
DISPLAY 0.510638 (-15500 3950);
DISPLAY INVISIBLE (-15500 3950);
FORCEPROP 2 LAST ROOM HSC1_BOM1
J 0
(-15200 4025);
DISPLAY 1.021277 (-15200 4025);
FORCEPROP 1 LAST PACK_TYPE 0402LF
J 0
(-15500 4000);
DISPLAY 0.510638 (-15500 4000);
FORCEPROP 1 LAST WATTAGE 1/16W
J 2
(-15200 4000);
DISPLAY 0.510638 (-15200 4000);
FORCEPROP 1 LAST VALUE 33.2
J 2
(-15200 3875);
DISPLAY 0.510638 (-15200 3875);
FORCEPROP 1 LAST TOLERANCE 1%
J 0
(-15175 3875);
DISPLAY 0.510638 (-15175 3875);
FORCEPROP 1 LAST MATERIAL CHIP
J 0
(-15100 3875);
DISPLAY 0.510638 (-15100 3875);
FORCEPROP 1 LAST LOCATION R3909
J 0
(-15675 3875);
DISPLAY 0.638298 (-15675 3875);
FORCEPROP 1 LASTPIN (-15500 3875) $PN 1
J 0
(-15488 3887);
DISPLAY 0.787234 (-15488 3887);
PAINT MONO (-15488 3887);
FORCEPROP 1 LASTPIN (-15300 3875) $PN 2
J 0
(-15338 3887);
DISPLAY 0.787234 (-15338 3887);
PAINT MONO (-15338 3887);
FORCEPROP 2 LAST CDS_LIB pure_quanta
J 0
(-15400 3875);
DISPLAY INVISIBLE (-15400 3875);
FORCEPROP 1 LAST PATH I38
J 0
(-15450 4025);
DISPLAY 0.978723 (-15450 4025);
PAINT WHITE (-15450 4025);
DISPLAY INVISIBLE (-15450 4025);
FORCEPROP 0 LAST $SEC 1
J 0
(-15200 4025);
DISPLAY 0.680851 (-15200 4025);
PAINT MONO (-15200 4025);
DISPLAY INVISIBLE (-15200 4025);
FORCEPROP 0 LAST CDS_SEC 1
J 0
(-15200 4025);
DISPLAY 1.021277 (-15200 4025);
DISPLAY INVISIBLE (-15200 4025);
FORCEADD UNIVERSAL_GND..1
(-15425 4275);
FORCEPROP 3 LASTPIN (-15425 4325) SIG_NAME AGND_HSC\g
J 0
(-15415 4335);
DISPLAY 0.659574 (-15415 4335);
PAINT MONO (-15415 4335);
DISPLAY INVISIBLE (-15415 4335);
FORCEPROP 1 LAST HDL_POWER AGND_HSC
J 1
(-15400 4200);
DISPLAY 0.723404 (-15400 4200);
PAINT GREEN (-15400 4200);
FORCEPROP 2 LAST CDS_LIB logical_power
J 0
(-15425 4275);
DISPLAY INVISIBLE (-15425 4275);
FORCEPROP 1 LAST PATH I39
J 0
(-15350 4275);
DISPLAY 0.872340 (-15350 4275);
PAINT AQUA (-15350 4275);
DISPLAY INVISIBLE (-15350 4275);
FORCEADD Q_RES..2
(-16525 450);
FORCEPROP 1 LAST PART_NUMBER CS33302FB00
J 0
(-16475 375);
DISPLAY 0.723404 (-16475 375);
PAINT WHITE (-16475 375);
DISPLAY INVISIBLE (-16475 375);
FORCEPROP 1 LAST WATTAGE 1/16W
J 0
(-16485 425);
DISPLAY 0.723404 (-16485 425);
PAINT SKYBLUE (-16485 425);
FORCEPROP 1 LAST PACK_TYPE 0402LF
J 0
(-16475 325);
DISPLAY 0.723404 (-16475 325);
PAINT SKYBLUE (-16475 325);
FORCEPROP 1 LAST VALUE 33K
J 0
(-16480 525);
DISPLAY 0.723404 (-16480 525);
PAINT SKYBLUE (-16480 525);
FORCEPROP 1 LAST TOLERANCE 1%
J 0
(-16480 475);
DISPLAY 0.723404 (-16480 475);
PAINT SKYBLUE (-16480 475);
FORCEPROP 1 LAST LOCATION R3907
J 0
(-16480 575);
DISPLAY 0.723404 (-16480 575);
PAINT AQUA (-16480 575);
FORCEPROP 2 LAST CDS_LIB pure_quanta
J 0
(-16525 450);
DISPLAY INVISIBLE (-16525 450);
FORCEPROP 1 LAST MATERIAL CHIP
J 0
(-16485 375);
DISPLAY 0.723404 (-16485 375);
PAINT SKYBLUE (-16485 375);
DISPLAY INVISIBLE (-16485 375);
FORCEPROP 1 LAST PATH I4
J 0
(-16475 625);
DISPLAY 0.978723 (-16475 625);
PAINT WHITE (-16475 625);
DISPLAY INVISIBLE (-16475 625);
FORCEPROP 0 LAST $SEC 1
J 0
(-16475 625);
DISPLAY INVISIBLE (-16475 625);
FORCEPROP 0 LAST CDS_SEC 1
J 0
(-16475 625);
DISPLAY INVISIBLE (-16475 625);
FORCEPROP 1 LASTPIN (-16525 550) $PN 1
J 0
(-16520 512);
DISPLAY 0.787234 (-16520 512);
PAINT MONO (-16520 512);
DISPLAY INVISIBLE (-16520 512);
FORCEPROP 1 LASTPIN (-16525 350) $PN 2
J 0
(-16520 360);
DISPLAY 0.787234 (-16520 360);
PAINT MONO (-16520 360);
DISPLAY INVISIBLE (-16520 360);
FORCEADD Q_RES..2
(-15425 4600);
FORCEPROP 1 LAST PART_NUMBER CS24992BB04
J 0
(-15385 4475);
DISPLAY 0.638298 (-15385 4475);
DISPLAY INVISIBLE (-15385 4475);
FORCEPROP 1 LAST TOLERANCE 0.1%
J 0
(-15380 4625);
DISPLAY 0.638298 (-15380 4625);
FORCEPROP 1 LAST PACK_TYPE 0402LF
J 0
(-15385 4425);
DISPLAY 0.638298 (-15385 4425);
FORCEPROP 2 LAST ROOM HSC1_BOM1
J 0
(-15375 4775);
DISPLAY 1.021277 (-15375 4775);
FORCEPROP 1 LAST MATERIAL CHIP
J 0
(-15385 4525);
DISPLAY 0.638298 (-15385 4525);
FORCEPROP 1 LAST WATTAGE 1/16W
J 0
(-15385 4575);
DISPLAY 0.638298 (-15385 4575);
FORCEPROP 1 LAST VALUE 4.99K
J 0
(-15380 4675);
DISPLAY 0.638298 (-15380 4675);
FORCEPROP 1 LAST LOCATION PR3927
J 0
(-15380 4725);
DISPLAY 0.978723 (-15380 4725);
FORCEPROP 1 LASTPIN (-15425 4700) $PN 1
J 0
(-15420 4662);
DISPLAY 0.787234 (-15420 4662);
PAINT MONO (-15420 4662);
FORCEPROP 1 LASTPIN (-15425 4500) $PN 2
J 0
(-15420 4510);
DISPLAY 0.787234 (-15420 4510);
PAINT MONO (-15420 4510);
FORCEPROP 2 LAST CDS_LIB pure_quanta
J 0
(-15425 4600);
DISPLAY INVISIBLE (-15425 4600);
FORCEPROP 1 LAST PATH I40
J 0
(-15375 4775);
DISPLAY 0.978723 (-15375 4775);
PAINT WHITE (-15375 4775);
DISPLAY INVISIBLE (-15375 4775);
FORCEPROP 0 LAST $SEC 1
J 0
(-15375 4775);
DISPLAY 0.680851 (-15375 4775);
PAINT MONO (-15375 4775);
DISPLAY INVISIBLE (-15375 4775);
FORCEPROP 0 LAST CDS_SEC 1
J 0
(-15375 4775);
DISPLAY 1.021277 (-15375 4775);
DISPLAY INVISIBLE (-15375 4775);
FORCEADD Q_RES..1
(-14825 3225);
FORCEPROP 1 LAST PART_NUMBER CS00002JB13
J 0
(-15150 3175);
DISPLAY 0.723404 (-15150 3175);
PAINT WHITE (-15150 3175);
DISPLAY INVISIBLE (-15150 3175);
FORCEPROP 1 LAST PACK_TYPE 0402LF
J 0
(-14650 3175);
DISPLAY 0.723404 (-14650 3175);
PAINT SKYBLUE (-14650 3175);
FORCEPROP 1 LAST TOLERANCE 5%
J 0
(-14750 3175);
DISPLAY 0.723404 (-14750 3175);
PAINT SKYBLUE (-14750 3175);
FORCEPROP 1 LAST VALUE 0
J 2
(-14675 3225);
DISPLAY 0.723404 (-14675 3225);
PAINT SKYBLUE (-14675 3225);
FORCEPROP 2 LAST ROOM HSC1_BOM1
J 0
(-14425 3275);
DISPLAY 1.021277 (-14425 3275);
FORCEPROP 1 LAST MATERIAL CHIP
J 0
(-14425 3175);
DISPLAY 0.723404 (-14425 3175);
PAINT SKYBLUE (-14425 3175);
FORCEPROP 1 LAST WATTAGE 1/16W
J 2
(-14425 3225);
DISPLAY 0.723404 (-14425 3225);
PAINT SKYBLUE (-14425 3225);
FORCEPROP 1 LAST LOCATION PR3928
J 0
(-15150 3225);
DISPLAY 0.723404 (-15150 3225);
PAINT AQUA (-15150 3225);
FORCEPROP 1 LASTPIN (-14925 3225) $PN 1
J 0
(-14913 3237);
DISPLAY 0.787234 (-14913 3237);
PAINT MONO (-14913 3237);
FORCEPROP 1 LASTPIN (-14725 3225) $PN 2
J 0
(-14763 3237);
DISPLAY 0.787234 (-14763 3237);
PAINT MONO (-14763 3237);
FORCEPROP 2 LAST CDS_LIB pure_quanta
J 0
(-14825 3225);
DISPLAY INVISIBLE (-14825 3225);
FORCEPROP 1 LAST PATH I41
J 0
(-14875 3375);
DISPLAY 0.978723 (-14875 3375);
PAINT WHITE (-14875 3375);
DISPLAY INVISIBLE (-14875 3375);
FORCEPROP 0 LAST $SEC 1
J 0
(-14425 3275);
DISPLAY 0.680851 (-14425 3275);
PAINT MONO (-14425 3275);
DISPLAY INVISIBLE (-14425 3275);
FORCEPROP 0 LAST CDS_SEC 1
J 0
(-14425 3275);
DISPLAY 1.021277 (-14425 3275);
DISPLAY INVISIBLE (-14425 3275);
FORCEADD Q_RES..1
R 1
(-14575 2850);
FORCEPROP 1 LAST PART_NUMBER CS21002FB06
J 0
(-14500 2750);
DISPLAY 0.723404 (-14500 2750);
PAINT WHITE (-14500 2750);
DISPLAY INVISIBLE (-14500 2750);
FORCEPROP 1 LAST PACK_TYPE 0402LF
J 0
(-14500 2850);
DISPLAY 0.723404 (-14500 2850);
PAINT SKYBLUE (-14500 2850);
FORCEPROP 1 LAST TOLERANCE 1%
J 0
(-14500 2900);
DISPLAY 0.723404 (-14500 2900);
PAINT SKYBLUE (-14500 2900);
FORCEPROP 1 LAST VALUE 1K
J 0
(-14500 2950);
DISPLAY 0.723404 (-14500 2950);
PAINT SKYBLUE (-14500 2950);
FORCEPROP 1 LAST WATTAGE 1/16W
J 0
(-14500 2800);
DISPLAY 0.723404 (-14500 2800);
PAINT SKYBLUE (-14500 2800);
FORCEPROP 1 LAST MATERIAL EMPTY
J 0
(-14500 2700);
DISPLAY 0.638298 (-14500 2700);
PAINT RED (-14500 2700);
FORCEPROP 1 LAST LOCATION PR3929
J 0
(-14500 3000);
DISPLAY 0.723404 (-14500 3000);
PAINT AQUA (-14500 3000);
FORCEPROP 1 LASTPIN (-14575 2750) $PN 1
R 1
J 0
(-14587 2762);
DISPLAY 0.787234 (-14587 2762);
PAINT MONO (-14587 2762);
FORCEPROP 1 LASTPIN (-14575 2950) $PN 2
R 1
J 0
(-14587 2912);
DISPLAY 0.787234 (-14587 2912);
PAINT MONO (-14587 2912);
FORCEPROP 2 LAST CDS_LIB pure_quanta
J 0
(-14575 2850);
DISPLAY INVISIBLE (-14575 2850);
FORCEPROP 1 LAST PATH I42
R 1
J 0
(-14725 2800);
DISPLAY 0.978723 (-14725 2800);
PAINT WHITE (-14725 2800);
DISPLAY INVISIBLE (-14725 2800);
FORCEPROP 0 LAST $SEC 1
R 1
J 0
(-14500 3050);
DISPLAY 0.680851 (-14500 3050);
PAINT MONO (-14500 3050);
DISPLAY INVISIBLE (-14500 3050);
FORCEPROP 0 LAST CDS_SEC 1
R 1
J 0
(-14500 3050);
DISPLAY 1.021277 (-14500 3050);
DISPLAY INVISIBLE (-14500 3050);
FORCEADD Q_RES..1
(-14825 3475);
FORCEPROP 1 LAST PART_NUMBER CS31002FB08
J 0
(-15150 3425);
DISPLAY 0.723404 (-15150 3425);
PAINT WHITE (-15150 3425);
DISPLAY INVISIBLE (-15150 3425);
FORCEPROP 1 LAST WATTAGE 1/16W
J 2
(-14425 3475);
DISPLAY 0.723404 (-14425 3475);
PAINT SKYBLUE (-14425 3475);
FORCEPROP 1 LAST VALUE 10K
J 2
(-14650 3475);
DISPLAY 0.723404 (-14650 3475);
PAINT SKYBLUE (-14650 3475);
FORCEPROP 1 LAST TOLERANCE 1%
J 0
(-14750 3425);
DISPLAY 0.723404 (-14750 3425);
PAINT SKYBLUE (-14750 3425);
FORCEPROP 1 LAST PACK_TYPE 0402LF
J 0
(-14650 3425);
DISPLAY 0.723404 (-14650 3425);
PAINT SKYBLUE (-14650 3425);
FORCEPROP 2 LAST ROOM HSC1_BOM1
J 0
(-14425 3525);
DISPLAY 1.021277 (-14425 3525);
FORCEPROP 1 LAST MATERIAL CHIP
J 0
(-14425 3425);
DISPLAY 0.723404 (-14425 3425);
PAINT SKYBLUE (-14425 3425);
FORCEPROP 1 LAST $LOCATION PR2106
J 0
(-15150 3475);
DISPLAY 0.723404 (-15150 3475);
PAINT AQUA (-15150 3475);
FORCEPROP 1 LASTPIN (-14925 3475) $PN 1
J 0
(-14913 3487);
DISPLAY 0.787234 (-14913 3487);
PAINT MONO (-14913 3487);
FORCEPROP 1 LASTPIN (-14725 3475) $PN 2
J 0
(-14763 3487);
DISPLAY 0.787234 (-14763 3487);
PAINT MONO (-14763 3487);
FORCEPROP 2 LAST CDS_LIB pure_quanta
J 0
(-14825 3475);
DISPLAY INVISIBLE (-14825 3475);
FORCEPROP 1 LAST PATH I43
J 0
(-14875 3625);
DISPLAY 0.978723 (-14875 3625);
PAINT WHITE (-14875 3625);
DISPLAY INVISIBLE (-14875 3625);
FORCEPROP 0 LAST CDS_LOCATION PR2106
J 0
(-14425 3525);
DISPLAY 1.021277 (-14425 3525);
DISPLAY INVISIBLE (-14425 3525);
FORCEPROP 0 LAST $SEC 1
J 0
(-14425 3525);
DISPLAY 0.680851 (-14425 3525);
PAINT MONO (-14425 3525);
DISPLAY INVISIBLE (-14425 3525);
FORCEPROP 0 LAST CDS_SEC 1
J 0
(-14425 3525);
DISPLAY 1.021277 (-14425 3525);
DISPLAY INVISIBLE (-14425 3525);
FORCEADD Q_RES..1
(-14825 3350);
FORCEPROP 1 LAST PART_NUMBER CS00002JB13
J 0
(-15150 3300);
DISPLAY 0.723404 (-15150 3300);
PAINT WHITE (-15150 3300);
DISPLAY INVISIBLE (-15150 3300);
FORCEPROP 1 LAST TOLERANCE 5%
J 0
(-14750 3300);
DISPLAY 0.723404 (-14750 3300);
PAINT SKYBLUE (-14750 3300);
FORCEPROP 1 LAST VALUE 0
J 2
(-14675 3350);
DISPLAY 0.723404 (-14675 3350);
PAINT SKYBLUE (-14675 3350);
FORCEPROP 2 LAST ROOM HSC1_BOM1
J 0
(-14425 3400);
DISPLAY 1.021277 (-14425 3400);
FORCEPROP 1 LAST PACK_TYPE 0402LF
J 0
(-14650 3300);
DISPLAY 0.723404 (-14650 3300);
PAINT SKYBLUE (-14650 3300);
FORCEPROP 1 LAST MATERIAL CHIP
J 0
(-14425 3300);
DISPLAY 0.723404 (-14425 3300);
PAINT SKYBLUE (-14425 3300);
FORCEPROP 1 LAST WATTAGE 1/16W
J 2
(-14425 3350);
DISPLAY 0.723404 (-14425 3350);
PAINT SKYBLUE (-14425 3350);
FORCEPROP 1 LAST LOCATION R2586
J 0
(-15150 3350);
DISPLAY 0.723404 (-15150 3350);
PAINT AQUA (-15150 3350);
FORCEPROP 1 LASTPIN (-14925 3350) $PN 1
J 0
(-14913 3362);
DISPLAY 0.787234 (-14913 3362);
PAINT MONO (-14913 3362);
FORCEPROP 1 LASTPIN (-14725 3350) $PN 2
J 0
(-14763 3362);
DISPLAY 0.787234 (-14763 3362);
PAINT MONO (-14763 3362);
FORCEPROP 2 LAST CDS_LIB pure_quanta
J 0
(-14825 3350);
DISPLAY INVISIBLE (-14825 3350);
FORCEPROP 1 LAST PATH I44
J 0
(-14875 3500);
DISPLAY 0.978723 (-14875 3500);
PAINT WHITE (-14875 3500);
DISPLAY INVISIBLE (-14875 3500);
FORCEPROP 0 LAST $SEC 1
J 0
(-14425 3400);
DISPLAY 0.680851 (-14425 3400);
PAINT MONO (-14425 3400);
DISPLAY INVISIBLE (-14425 3400);
FORCEPROP 0 LAST CDS_SEC 1
J 0
(-14425 3400);
DISPLAY 1.021277 (-14425 3400);
DISPLAY INVISIBLE (-14425 3400);
FORCEADD Q_CAP..1
(-14900 4600);
FORCEPROP 1 LAST PART_NUMBER CH31006KB18
J 0
(-14825 4475);
DISPLAY 0.723404 (-14825 4475);
PAINT WHITE (-14825 4475);
DISPLAY INVISIBLE (-14825 4475);
FORCEPROP 1 LAST VOLTAGE 50V
J 0
(-14825 4575);
DISPLAY 0.723404 (-14825 4575);
PAINT SKYBLUE (-14825 4575);
FORCEPROP 1 LAST MATERIAL X7R
J 0
(-14825 4525);
DISPLAY 0.723404 (-14825 4525);
PAINT SKYBLUE (-14825 4525);
FORCEPROP 1 LAST PACK_TYPE C0402
J 0
(-14825 4425);
DISPLAY 0.723404 (-14825 4425);
PAINT SKYBLUE (-14825 4425);
FORCEPROP 2 LAST ROOM HSC1_BOM1
J 0
(-14825 4725);
DISPLAY 1.021277 (-14825 4725);
FORCEPROP 1 LAST VALUE 0.01UF
J 0
(-14825 4625);
DISPLAY 0.723404 (-14825 4625);
PAINT SKYBLUE (-14825 4625);
FORCEPROP 1 LAST LOCATION PC2189
J 0
(-14825 4675);
DISPLAY 0.723404 (-14825 4675);
PAINT AQUA (-14825 4675);
FORCEPROP 1 LASTPIN (-14900 4700) $PN 1
J 0
(-14890 4680);
DISPLAY 0.787234 (-14890 4680);
PAINT MONO (-14890 4680);
FORCEPROP 1 LASTPIN (-14900 4500) $PN 2
J 0
(-14890 4480);
DISPLAY 0.787234 (-14890 4480);
PAINT MONO (-14890 4480);
FORCEPROP 1 LAST TOLERANCE 10%
J 0
(-14850 4550);
DISPLAY 0.978723 (-14850 4550);
PAINT SKYBLUE (-14850 4550);
DISPLAY INVISIBLE (-14850 4550);
FORCEPROP 2 LAST CDS_LIB pure_quanta
J 0
(-14900 4600);
DISPLAY INVISIBLE (-14900 4600);
FORCEPROP 1 LAST PATH I45
J 0
(-14850 4750);
DISPLAY 0.978723 (-14850 4750);
PAINT WHITE (-14850 4750);
DISPLAY INVISIBLE (-14850 4750);
FORCEPROP 0 LAST $SEC 1
J 0
(-14825 4800);
DISPLAY 0.680851 (-14825 4800);
PAINT MONO (-14825 4800);
DISPLAY INVISIBLE (-14825 4800);
FORCEPROP 0 LAST CDS_SEC 1
J 0
(-14825 4800);
DISPLAY 1.021277 (-14825 4800);
DISPLAY INVISIBLE (-14825 4800);
FORCEADD UNIVERSAL_POWER..1
(-16950 4975);
FORCEPROP 3 LASTPIN (-16950 4925) SIG_NAME HSC_VDD\g
J 0
(-16940 4935);
DISPLAY 0.659574 (-16940 4935);
PAINT MONO (-16940 4935);
DISPLAY INVISIBLE (-16940 4935);
FORCEPROP 1 LAST HDL_POWER HSC_VDD
J 1
(-16950 5025);
DISPLAY 0.723404 (-16950 5025);
PAINT GREEN (-16950 5025);
FORCEPROP 2 LAST CDS_LIB logical_power
J 0
(-16950 4975);
DISPLAY INVISIBLE (-16950 4975);
FORCEPROP 2 LAST BOM_COST MIO_VRD_SB
J 0
(-16950 5075);
DISPLAY 0.617021 (-16950 5075);
PAINT PURPLE (-16950 5075);
DISPLAY INVISIBLE (-16950 5075);
FORCEPROP 1 LAST PATH I47
J 0
(-16900 5000);
DISPLAY 0.872340 (-16900 5000);
PAINT AQUA (-16900 5000);
DISPLAY INVISIBLE (-16900 5000);
FORCEADD MOSFET_NCH_GDS_ESD_PROTECTED..1
(-16025 625);
FORCEPROP 1 LAST PART_NUMBER BAM70020002
J 0
(-15883 537);
DISPLAY 0.574468 (-15883 537);
PAINT GREEN (-15883 537);
DISPLAY INVISIBLE (-15883 537);
FORCEPROP 2 LAST VALUE 2N7002K
J 0
(-15875 625);
DISPLAY 0.808511 (-15875 625);
FORCEPROP 2 LAST PART_TYPE SMLF
J 0
(-15875 675);
DISPLAY 0.808511 (-15875 675);
FORCEPROP 1 LAST MATERIAL IC
J 0
(-15883 480);
DISPLAY 0.574468 (-15883 480);
PAINT GREEN (-15883 480);
FORCEPROP 1 LAST $LOCATION U290
J 0
(-15883 589);
DISPLAY 0.574468 (-15883 589);
PAINT GREEN (-15883 589);
FORCEPROP 0 LASTPIN (-16000 825) $PN D
R 1
J 0
(-16010 835);
DISPLAY 0.680851 (-16010 835);
PAINT MONO (-16010 835);
FORCEPROP 0 LASTPIN (-16200 625) $PN G
J 2
(-16210 635);
DISPLAY 0.680851 (-16210 635);
PAINT MONO (-16210 635);
FORCEPROP 0 LASTPIN (-16000 425) $PN S
R 1
J 2
(-16010 415);
DISPLAY 0.680851 (-16010 415);
PAINT MONO (-16010 415);
FORCEPROP 1 LAST CDS_LMAN_SYM_OUTLINE -125,150,125,-150
J 0
(-16025 625);
DISPLAY 0.468085 (-16025 625);
PAINT GREEN (-16025 625);
DISPLAY INVISIBLE (-16025 625);
FORCEPROP 2 LAST CDS_LIB pure_quanta
J 0
(-16025 625);
DISPLAY INVISIBLE (-16025 625);
FORCEPROP 1 LAST NEEDS_NO_SIZE TRUE
J 0
(-15900 515);
DISPLAY 0.723404 (-15900 515);
PAINT GREEN (-15900 515);
DISPLAY INVISIBLE (-15900 515);
FORCEPROP 1 LAST PATH I5
J 0
(-15900 475);
DISPLAY 0.723404 (-15900 475);
PAINT GREEN (-15900 475);
DISPLAY INVISIBLE (-15900 475);
FORCEPROP 0 LAST CDS_LOCATION U290
J 0
(-15875 725);
DISPLAY 1.021277 (-15875 725);
DISPLAY INVISIBLE (-15875 725);
FORCEPROP 0 LAST $SEC 1
J 0
(-15875 725);
DISPLAY 0.680851 (-15875 725);
PAINT MONO (-15875 725);
DISPLAY INVISIBLE (-15875 725);
FORCEPROP 0 LAST CDS_SEC 1
J 0
(-15875 725);
DISPLAY 1.021277 (-15875 725);
DISPLAY INVISIBLE (-15875 725);
FORCEADD UNIVERSAL_POWER..1
(-15950 5650);
FORCEPROP 3 LASTPIN (-15950 5600) SIG_NAME P12V_PSU\g
J 0
(-15940 5610);
DISPLAY 0.659574 (-15940 5610);
PAINT MONO (-15940 5610);
DISPLAY INVISIBLE (-15940 5610);
FORCEPROP 1 LAST HDL_POWER P12V_PSU
J 1
(-15950 5700);
DISPLAY 0.723404 (-15950 5700);
PAINT GREEN (-15950 5700);
FORCEPROP 2 LAST BOM_COST MIO_VRD_SB
J 0
(-15950 5750);
DISPLAY 0.617021 (-15950 5750);
PAINT PURPLE (-15950 5750);
DISPLAY INVISIBLE (-15950 5750);
FORCEPROP 2 LAST CDS_LIB logical_power
J 0
(-15950 5650);
DISPLAY INVISIBLE (-15950 5650);
FORCEPROP 1 LAST PATH I50
J 0
(-15900 5675);
DISPLAY 0.872340 (-15900 5675);
PAINT AQUA (-15900 5675);
DISPLAY INVISIBLE (-15900 5675);
FORCEADD Q_CAP..1
(-15950 5050);
FORCEPROP 1 LAST PART_NUMBER CH5104KEB02
J 0
(-15900 4950);
DISPLAY 0.723404 (-15900 4950);
PAINT WHITE (-15900 4950);
DISPLAY INVISIBLE (-15900 4950);
FORCEPROP 1 LAST PACK_TYPE C0402
J 0
(-15900 4900);
DISPLAY 0.723404 (-15900 4900);
PAINT SKYBLUE (-15900 4900);
FORCEPROP 1 LAST MATERIAL X6S
J 0
(-15900 5000);
DISPLAY 0.723404 (-15900 5000);
PAINT SKYBLUE (-15900 5000);
FORCEPROP 2 LAST ROOM HSC1_BOM1
J 0
(-15900 5200);
DISPLAY 1.021277 (-15900 5200);
FORCEPROP 1 LAST VALUE 1UF
J 0
(-15900 5100);
DISPLAY 0.723404 (-15900 5100);
PAINT SKYBLUE (-15900 5100);
FORCEPROP 1 LAST VOLTAGE 25V
J 0
(-15900 5050);
DISPLAY 0.723404 (-15900 5050);
PAINT SKYBLUE (-15900 5050);
FORCEPROP 1 LAST LOCATION PC2188
J 0
(-15900 5150);
DISPLAY 0.723404 (-15900 5150);
PAINT AQUA (-15900 5150);
FORCEPROP 1 LASTPIN (-15950 5150) $PN 1
J 0
(-15940 5130);
DISPLAY 0.787234 (-15940 5130);
PAINT MONO (-15940 5130);
FORCEPROP 1 LASTPIN (-15950 4950) $PN 2
J 0
(-15940 4930);
DISPLAY 0.787234 (-15940 4930);
PAINT MONO (-15940 4930);
FORCEPROP 1 LAST TOLERANCE 10%
J 0
(-15900 5000);
DISPLAY 0.978723 (-15900 5000);
PAINT SKYBLUE (-15900 5000);
DISPLAY INVISIBLE (-15900 5000);
FORCEPROP 2 LAST CDS_LIB pure_quanta
J 0
(-15950 5050);
DISPLAY INVISIBLE (-15950 5050);
FORCEPROP 1 LAST PATH I51
J 0
(-15900 5200);
DISPLAY 0.978723 (-15900 5200);
PAINT WHITE (-15900 5200);
DISPLAY INVISIBLE (-15900 5200);
FORCEPROP 0 LAST $SEC 1
J 0
(-15900 5200);
DISPLAY 0.680851 (-15900 5200);
PAINT MONO (-15900 5200);
DISPLAY INVISIBLE (-15900 5200);
FORCEPROP 0 LAST CDS_SEC 1
J 0
(-15900 5200);
DISPLAY 1.021277 (-15900 5200);
DISPLAY INVISIBLE (-15900 5200);
FORCEADD Q_RES..2
(-15425 5050);
FORCEPROP 1 LAST PART_NUMBER CS37502BB01
J 0
(-15385 4925);
DISPLAY 0.787234 (-15385 4925);
DISPLAY INVISIBLE (-15385 4925);
FORCEPROP 2 LAST ROOM HSC1_BOM1
J 0
(-15375 5225);
DISPLAY 1.021277 (-15375 5225);
FORCEPROP 1 LAST TOLERANCE 0.1%
J 0
(-15380 5075);
DISPLAY 0.787234 (-15380 5075);
FORCEPROP 1 LAST WATTAGE 1/16W
J 0
(-15385 5025);
DISPLAY 0.787234 (-15385 5025);
FORCEPROP 1 LAST VALUE 75K
J 0
(-15380 5125);
DISPLAY 0.787234 (-15380 5125);
FORCEPROP 1 LAST PACK_TYPE 0402LF
J 0
(-15385 4875);
DISPLAY 0.787234 (-15385 4875);
FORCEPROP 1 LAST MATERIAL CHIP
J 0
(-15385 4975);
DISPLAY 0.787234 (-15385 4975);
FORCEPROP 1 LAST LOCATION PR3926
J 0
(-15380 5175);
DISPLAY 0.978723 (-15380 5175);
FORCEPROP 1 LASTPIN (-15425 5150) $PN 1
J 0
(-15420 5112);
DISPLAY 0.787234 (-15420 5112);
PAINT MONO (-15420 5112);
FORCEPROP 1 LASTPIN (-15425 4950) $PN 2
J 0
(-15420 4960);
DISPLAY 0.787234 (-15420 4960);
PAINT MONO (-15420 4960);
FORCEPROP 2 LAST CDS_LIB pure_quanta
J 0
(-15425 5050);
DISPLAY INVISIBLE (-15425 5050);
FORCEPROP 1 LAST PATH I52
J 0
(-15375 5225);
DISPLAY 0.978723 (-15375 5225);
PAINT WHITE (-15375 5225);
DISPLAY INVISIBLE (-15375 5225);
FORCEPROP 0 LAST $SEC 1
J 0
(-15375 5225);
DISPLAY 0.680851 (-15375 5225);
PAINT MONO (-15375 5225);
DISPLAY INVISIBLE (-15375 5225);
FORCEPROP 0 LAST CDS_SEC 1
J 0
(-15375 5225);
DISPLAY 1.021277 (-15375 5225);
DISPLAY INVISIBLE (-15375 5225);
FORCEADD GND..1
(-13500 1475);
FORCEPROP 3 LASTPIN (-13500 1525) SIG_NAME GND\g
J 0
(-13490 1535);
DISPLAY 0.659574 (-13490 1535);
PAINT MONO (-13490 1535);
DISPLAY INVISIBLE (-13490 1535);
FORCEPROP 1 LAST HDL_POWER GND
J 0
(-13500 1625);
DISPLAY 1.170213 (-13500 1625);
PAINT GREEN (-13500 1625);
DISPLAY INVISIBLE (-13500 1625);
FORCEPROP 2 LAST CDS_LIB logical_power
J 0
(-13500 1475);
DISPLAY INVISIBLE (-13500 1475);
FORCEPROP 1 LAST SIZE 1B
J 0
(-13425 1425);
DISPLAY 0.872340 (-13425 1425);
PAINT AQUA (-13425 1425);
DISPLAY INVISIBLE (-13425 1425);
FORCEPROP 1 LAST PATH I53
J 0
(-13425 1475);
DISPLAY 0.872340 (-13425 1475);
PAINT AQUA (-13425 1475);
DISPLAY INVISIBLE (-13425 1475);
FORCEADD Q_RES..1
(-13175 1725);
FORCEPROP 1 LAST PART_NUMBER CS00002JB13
J 0
(-13050 1775);
DISPLAY 0.723404 (-13050 1775);
PAINT WHITE (-13050 1775);
DISPLAY INVISIBLE (-13050 1775);
FORCEPROP 1 LAST PACK_TYPE 0402LF
J 0
(-13000 1550);
DISPLAY 0.723404 (-13000 1550);
PAINT SKYBLUE (-13000 1550);
FORCEPROP 1 LAST TOLERANCE 5%
J 0
(-13075 1650);
DISPLAY 0.723404 (-13075 1650);
PAINT SKYBLUE (-13075 1650);
FORCEPROP 1 LAST WATTAGE 1/16W
J 2
(-13275 1550);
DISPLAY 0.723404 (-13275 1550);
PAINT SKYBLUE (-13275 1550);
FORCEPROP 1 LAST MATERIAL CHIP
J 0
(-13250 1550);
DISPLAY 0.723404 (-13250 1550);
PAINT SKYBLUE (-13250 1550);
FORCEPROP 1 LAST VALUE 0
J 2
(-13225 1650);
DISPLAY 0.723404 (-13225 1650);
PAINT SKYBLUE (-13225 1650);
FORCEPROP 1 LAST LOCATION PR3002
J 0
(-13225 1775);
DISPLAY 0.723404 (-13225 1775);
PAINT AQUA (-13225 1775);
FORCEPROP 1 LASTPIN (-13275 1725) $PN 1
J 0
(-13263 1737);
DISPLAY 0.787234 (-13263 1737);
PAINT MONO (-13263 1737);
FORCEPROP 1 LASTPIN (-13075 1725) $PN 2
J 0
(-13113 1737);
DISPLAY 0.787234 (-13113 1737);
PAINT MONO (-13113 1737);
FORCEPROP 2 LAST CDS_LIB pure_quanta
J 0
(-13175 1725);
DISPLAY INVISIBLE (-13175 1725);
FORCEPROP 1 LAST PATH I54
J 0
(-13225 1875);
DISPLAY 0.978723 (-13225 1875);
PAINT WHITE (-13225 1875);
DISPLAY INVISIBLE (-13225 1875);
FORCEPROP 0 LAST $SEC 1
J 0
(-13050 1825);
DISPLAY 0.680851 (-13050 1825);
PAINT MONO (-13050 1825);
DISPLAY INVISIBLE (-13050 1825);
FORCEPROP 0 LAST CDS_SEC 1
J 0
(-13050 1825);
DISPLAY 1.021277 (-13050 1825);
DISPLAY INVISIBLE (-13050 1825);
FORCEADD UNIVERSAL_GND..1
(-13800 2625);
FORCEPROP 3 LASTPIN (-13800 2675) SIG_NAME AGND_HSC\g
J 0
(-13790 2685);
DISPLAY 0.659574 (-13790 2685);
PAINT MONO (-13790 2685);
DISPLAY INVISIBLE (-13790 2685);
FORCEPROP 1 LAST HDL_POWER AGND_HSC
J 1
(-13775 2550);
DISPLAY 0.723404 (-13775 2550);
PAINT GREEN (-13775 2550);
FORCEPROP 2 LAST CDS_LIB logical_power
J 0
(-13800 2625);
DISPLAY INVISIBLE (-13800 2625);
FORCEPROP 1 LAST PATH I55
J 0
(-13725 2625);
DISPLAY 0.872340 (-13725 2625);
PAINT AQUA (-13725 2625);
DISPLAY INVISIBLE (-13725 2625);
FORCEADD MP5990GMA1111Z..1
(-13125 3750);
FORCEPROP 1 LAST PART_NUMBER AL005990A03
J 0
(-13525 5000);
DISPLAY 0.723404 (-13525 5000);
PAINT GREEN (-13525 5000);
DISPLAY INVISIBLE (-13525 5000);
FORCEPROP 2 LASTPIN (-12550 4275) SIG_NAME HSC_VOSEN
J 0
(-12435 4285);
DISPLAY 0.808511 (-12435 4285);
FORCEPROP 2 LAST ROOM HSC1_BOM1
J 0
(-13525 5200);
DISPLAY 1.021277 (-13525 5200);
FORCEPROP 2 LAST PART_TYPE SMLF
J 0
(-13525 5150);
DISPLAY 1.021277 (-13525 5150);
FORCEPROP 2 LAST VALUE MP5990GMA-1111-Z
J 0
(-13525 5100);
DISPLAY 1.021277 (-13525 5100);
FORCEPROP 1 LAST MATERIAL IC
J 0
(-13545 4887);
DISPLAY 0.723404 (-13545 4887);
PAINT GREEN (-13545 4887);
FORCEPROP 1 LAST LOCATION PU289
J 0
(-13525 5050);
DISPLAY 0.723404 (-13525 5050);
PAINT GREEN (-13525 5050);
FORCEPROP 0 LASTPIN (-13700 2925) $PN 23
J 2
(-13710 2935);
DISPLAY 0.680851 (-13710 2935);
PAINT MONO (-13710 2935);
FORCEPROP 0 LASTPIN (-13700 3675) $PN 10
J 2
(-13710 3685);
DISPLAY 0.680851 (-13710 3685);
PAINT MONO (-13710 3685);
FORCEPROP 0 LASTPIN (-12550 3675) $PN 20
J 0
(-12540 3685);
DISPLAY 0.680851 (-12540 3685);
PAINT MONO (-12540 3685);
FORCEPROP 0 LASTPIN (-12550 3975) $PN 37
J 0
(-12540 3985);
DISPLAY 0.680851 (-12540 3985);
PAINT MONO (-12540 3985);
FORCEPROP 0 LASTPIN (-13700 3475) $PN 26
J 2
(-13710 3485);
DISPLAY 0.680851 (-13710 3485);
PAINT MONO (-13710 3485);
FORCEPROP 0 LASTPIN (-12550 2975) $PN 40
J 0
(-12540 2985);
DISPLAY 0.680851 (-12540 2985);
PAINT MONO (-12540 2985);
FORCEPROP 0 LASTPIN (-13700 2775) $PN 18
J 2
(-13710 2785);
DISPLAY 0.680851 (-13710 2785);
PAINT MONO (-13710 2785);
FORCEPROP 0 LASTPIN (-13700 2725) $PN 44
J 2
(-13710 2735);
DISPLAY 0.680851 (-13710 2735);
PAINT MONO (-13710 2735);
FORCEPROP 0 LASTPIN (-12550 4075) $PN 39
J 0
(-12540 4085);
DISPLAY 0.680851 (-12540 4085);
PAINT MONO (-12540 4085);
FORCEPROP 0 LASTPIN (-12550 3775) $PN 21
J 0
(-12540 3785);
DISPLAY 0.680851 (-12540 3785);
PAINT MONO (-12540 3785);
FORCEPROP 0 LASTPIN (-12550 3875) $PN 41
J 0
(-12540 3885);
DISPLAY 0.680851 (-12540 3885);
PAINT MONO (-12540 3885);
FORCEPROP 0 LASTPIN (-12550 3275) $PN 22
J 0
(-12540 3285);
DISPLAY 0.680851 (-12540 3285);
PAINT MONO (-12540 3285);
FORCEPROP 0 LASTPIN (-13700 3225) $PN 38
J 2
(-13710 3235);
DISPLAY 0.680851 (-13710 3235);
PAINT MONO (-13710 3235);
FORCEPROP 0 LASTPIN (-12550 2775) $PN 13
J 0
(-12540 2785);
DISPLAY 0.680851 (-12540 2785);
PAINT MONO (-12540 2785);
FORCEPROP 0 LASTPIN (-13700 3875) $PN 11
J 2
(-13710 3885);
DISPLAY 0.680851 (-13710 3885);
PAINT MONO (-13710 3885);
FORCEPROP 0 LASTPIN (-12550 3175) $PN 25
J 0
(-12540 3185);
DISPLAY 0.680851 (-12540 3185);
PAINT MONO (-12540 3185);
FORCEPROP 0 LASTPIN (-13700 3775) $PN 12
J 2
(-13710 3785);
DISPLAY 0.680851 (-13710 3785);
PAINT MONO (-13710 3785);
FORCEPROP 0 LASTPIN (-12550 3075) $PN 16
J 0
(-12540 3085);
DISPLAY 0.680851 (-12540 3085);
PAINT MONO (-12540 3085);
FORCEPROP 0 LASTPIN (-13700 3075) $PN 19
J 2
(-13710 3085);
DISPLAY 0.680851 (-13710 3085);
PAINT MONO (-13710 3085);
FORCEPROP 0 LASTPIN (-13700 4075) $PN 17
J 2
(-13710 4085);
DISPLAY 0.680851 (-13710 4085);
PAINT MONO (-13710 4085);
FORCEPROP 0 LASTPIN (-13700 4025) $PN 45
J 2
(-13710 4035);
DISPLAY 0.680851 (-13710 4035);
PAINT MONO (-13710 4035);
FORCEPROP 0 LASTPIN (-13700 4825) $PN 1
J 2
(-13710 4835);
DISPLAY 0.680851 (-13710 4835);
PAINT MONO (-13710 4835);
FORCEPROP 0 LASTPIN (-13700 4775) $PN 2
J 2
(-13710 4785);
DISPLAY 0.680851 (-13710 4785);
PAINT MONO (-13710 4785);
FORCEPROP 0 LASTPIN (-13700 4725) $PN 3
J 2
(-13710 4735);
DISPLAY 0.680851 (-13710 4735);
PAINT MONO (-13710 4735);
FORCEPROP 0 LASTPIN (-13700 4675) $PN 4
J 2
(-13710 4685);
DISPLAY 0.680851 (-13710 4685);
PAINT MONO (-13710 4685);
FORCEPROP 0 LASTPIN (-13700 4625) $PN 5
J 2
(-13710 4635);
DISPLAY 0.680851 (-13710 4635);
PAINT MONO (-13710 4635);
FORCEPROP 0 LASTPIN (-13700 4575) $PN 6
J 2
(-13710 4585);
DISPLAY 0.680851 (-13710 4585);
PAINT MONO (-13710 4585);
FORCEPROP 0 LASTPIN (-13700 4525) $PN 7
J 2
(-13710 4535);
DISPLAY 0.680851 (-13710 4535);
PAINT MONO (-13710 4535);
FORCEPROP 0 LASTPIN (-13700 4475) $PN 8
J 2
(-13710 4485);
DISPLAY 0.680851 (-13710 4485);
PAINT MONO (-13710 4485);
FORCEPROP 0 LASTPIN (-13700 4425) $PN 42
J 2
(-13710 4435);
DISPLAY 0.680851 (-13710 4435);
PAINT MONO (-13710 4435);
FORCEPROP 0 LASTPIN (-13700 4375) $PN 43
J 2
(-13710 4385);
DISPLAY 0.680851 (-13710 4385);
PAINT MONO (-13710 4385);
FORCEPROP 0 LASTPIN (-13700 3575) $PN 14
J 2
(-13710 3585);
DISPLAY 0.680851 (-13710 3585);
PAINT MONO (-13710 3585);
FORCEPROP 0 LASTPIN (-13700 4275) $PN 9
J 2
(-13710 4285);
DISPLAY 0.680851 (-13710 4285);
PAINT MONO (-13710 4285);
FORCEPROP 0 LASTPIN (-12550 4275) $PN 24
J 0
(-12540 4285);
DISPLAY 0.680851 (-12540 4285);
PAINT MONO (-12540 4285);
FORCEPROP 0 LASTPIN (-12550 4825) $PN 27
J 0
(-12540 4835);
DISPLAY 0.680851 (-12540 4835);
PAINT MONO (-12540 4835);
FORCEPROP 0 LASTPIN (-12550 4775) $PN 28
J 0
(-12540 4785);
DISPLAY 0.680851 (-12540 4785);
PAINT MONO (-12540 4785);
FORCEPROP 0 LASTPIN (-12550 4725) $PN 29
J 0
(-12540 4735);
DISPLAY 0.680851 (-12540 4735);
PAINT MONO (-12540 4735);
FORCEPROP 0 LASTPIN (-12550 4675) $PN 30
J 0
(-12540 4685);
DISPLAY 0.680851 (-12540 4685);
PAINT MONO (-12540 4685);
FORCEPROP 0 LASTPIN (-12550 4625) $PN 31
J 0
(-12540 4635);
DISPLAY 0.680851 (-12540 4635);
PAINT MONO (-12540 4635);
FORCEPROP 0 LASTPIN (-12550 4575) $PN 32
J 0
(-12540 4585);
DISPLAY 0.680851 (-12540 4585);
PAINT MONO (-12540 4585);
FORCEPROP 0 LASTPIN (-12550 4525) $PN 33
J 0
(-12540 4535);
DISPLAY 0.680851 (-12540 4535);
PAINT MONO (-12540 4535);
FORCEPROP 0 LASTPIN (-12550 4475) $PN 34
J 0
(-12540 4485);
DISPLAY 0.680851 (-12540 4485);
PAINT MONO (-12540 4485);
FORCEPROP 0 LASTPIN (-12550 4425) $PN 35
J 0
(-12540 4435);
DISPLAY 0.680851 (-12540 4435);
PAINT MONO (-12540 4435);
FORCEPROP 0 LASTPIN (-12550 4375) $PN 36
J 0
(-12540 4385);
DISPLAY 0.680851 (-12540 4385);
PAINT MONO (-12540 4385);
FORCEPROP 0 LASTPIN (-12550 3375) $PN 15
J 0
(-12540 3385);
DISPLAY 0.680851 (-12540 3385);
PAINT MONO (-12540 3385);
FORCEPROP 2 LAST CDS_LIB pure_quanta
J 0
(-13125 3750);
DISPLAY INVISIBLE (-13125 3750);
FORCEPROP 1 LAST NEEDS_NO_SIZE TRUE
J 0
(-13125 3750);
DISPLAY 0.723404 (-13125 3750);
PAINT GREEN (-13125 3750);
DISPLAY INVISIBLE (-13125 3750);
FORCEPROP 1 LAST CDS_LMAN_SYM_OUTLINE -425,1125,425,-1125
J 0
(-13125 3750);
DISPLAY 0.468085 (-13125 3750);
PAINT GREEN (-13125 3750);
DISPLAY INVISIBLE (-13125 3750);
FORCEPROP 1 LAST PATH I56
J 0
(-13125 3750);
DISPLAY 0.723404 (-13125 3750);
PAINT GREEN (-13125 3750);
DISPLAY INVISIBLE (-13125 3750);
FORCEPROP 0 LAST $SEC 1
J 0
(-13525 5200);
DISPLAY 0.680851 (-13525 5200);
PAINT MONO (-13525 5200);
DISPLAY INVISIBLE (-13525 5200);
FORCEPROP 0 LAST CDS_SEC 1
J 0
(-13525 5200);
DISPLAY 1.021277 (-13525 5200);
DISPLAY INVISIBLE (-13525 5200);
FORCEADD UNIVERSAL_GND..1
(-12725 1525);
FORCEPROP 3 LASTPIN (-12725 1575) SIG_NAME AGND_HSC\g
J 0
(-12715 1585);
DISPLAY 0.659574 (-12715 1585);
PAINT MONO (-12715 1585);
DISPLAY INVISIBLE (-12715 1585);
FORCEPROP 1 LAST HDL_POWER AGND_HSC
J 1
(-12700 1450);
DISPLAY 0.723404 (-12700 1450);
PAINT GREEN (-12700 1450);
FORCEPROP 2 LAST CDS_LIB logical_power
J 0
(-12725 1525);
DISPLAY INVISIBLE (-12725 1525);
FORCEPROP 1 LAST PATH I57
J 0
(-12650 1525);
DISPLAY 0.872340 (-12650 1525);
PAINT AQUA (-12650 1525);
DISPLAY INVISIBLE (-12650 1525);
FORCEADD Q_RES..1
(-11875 3675);
FORCEPROP 1 LAST PART_NUMBER CS22002BB07
J 0
(-11750 3700);
DISPLAY 0.723404 (-11750 3700);
PAINT WHITE (-11750 3700);
DISPLAY INVISIBLE (-11750 3700);
FORCEPROP 1 LAST PACK_TYPE 0402LF
J 0
(-11700 3575);
DISPLAY 0.723404 (-11700 3575);
PAINT SKYBLUE (-11700 3575);
FORCEPROP 1 LAST WATTAGE 1/16W
J 2
(-11950 3575);
DISPLAY 0.723404 (-11950 3575);
PAINT SKYBLUE (-11950 3575);
FORCEPROP 2 LAST ROOM HSC1_BOM1
J 0
(-11750 3750);
DISPLAY 1.021277 (-11750 3750);
FORCEPROP 1 LAST TOLERANCE 0.1%
J 0
(-11775 3625);
DISPLAY 0.723404 (-11775 3625);
PAINT SKYBLUE (-11775 3625);
FORCEPROP 1 LAST VALUE 2K
J 2
(-11925 3625);
DISPLAY 0.723404 (-11925 3625);
PAINT SKYBLUE (-11925 3625);
FORCEPROP 1 LAST MATERIAL CHIP
J 0
(-11925 3575);
DISPLAY 0.723404 (-11925 3575);
PAINT SKYBLUE (-11925 3575);
FORCEPROP 1 LAST $LOCATION PR1131
J 0
(-12150 3700);
DISPLAY 0.723404 (-12150 3700);
PAINT AQUA (-12150 3700);
FORCEPROP 1 LASTPIN (-11975 3675) $PN 1
J 0
(-11963 3687);
DISPLAY 0.787234 (-11963 3687);
PAINT MONO (-11963 3687);
FORCEPROP 1 LASTPIN (-11775 3675) $PN 2
J 0
(-11813 3687);
DISPLAY 0.787234 (-11813 3687);
PAINT MONO (-11813 3687);
FORCEPROP 2 LAST CDS_LIB pure_quanta
J 0
(-11875 3675);
DISPLAY INVISIBLE (-11875 3675);
FORCEPROP 1 LAST PATH I58
J 0
(-11925 3825);
DISPLAY 0.978723 (-11925 3825);
PAINT WHITE (-11925 3825);
DISPLAY INVISIBLE (-11925 3825);
FORCEPROP 0 LAST CDS_LOCATION PR1131
J 0
(-11825 3750);
DISPLAY 1.021277 (-11825 3750);
DISPLAY INVISIBLE (-11825 3750);
FORCEPROP 0 LAST $SEC 1
J 0
(-11825 3750);
DISPLAY 0.680851 (-11825 3750);
PAINT MONO (-11825 3750);
DISPLAY INVISIBLE (-11825 3750);
FORCEPROP 0 LAST CDS_SEC 1
J 0
(-11825 3750);
DISPLAY 1.021277 (-11825 3750);
DISPLAY INVISIBLE (-11825 3750);
FORCEADD Q_RES..2
(-11975 4675);
FORCEPROP 1 LAST PART_NUMBER CS24992BB04
J 0
(-11935 4550);
DISPLAY 0.638298 (-11935 4550);
DISPLAY INVISIBLE (-11935 4550);
FORCEPROP 1 LAST VALUE 4.99K
J 0
(-11930 4750);
DISPLAY 0.638298 (-11930 4750);
FORCEPROP 1 LAST TOLERANCE 0.1%
J 0
(-11930 4700);
DISPLAY 0.638298 (-11930 4700);
FORCEPROP 2 LAST ROOM HSC1_BOM1
J 0
(-11925 4850);
DISPLAY 1.021277 (-11925 4850);
FORCEPROP 1 LAST WATTAGE 1/16W
J 0
(-11935 4650);
DISPLAY 0.638298 (-11935 4650);
FORCEPROP 1 LAST MATERIAL CHIP
J 0
(-11935 4600);
DISPLAY 0.638298 (-11935 4600);
FORCEPROP 1 LAST PACK_TYPE 0402LF
J 0
(-11935 4500);
DISPLAY 0.638298 (-11935 4500);
FORCEPROP 1 LAST LOCATION PR3932
J 0
(-11930 4800);
DISPLAY 0.978723 (-11930 4800);
FORCEPROP 1 LASTPIN (-11975 4775) $PN 1
J 0
(-11970 4737);
DISPLAY 0.787234 (-11970 4737);
PAINT MONO (-11970 4737);
FORCEPROP 1 LASTPIN (-11975 4575) $PN 2
J 0
(-11970 4585);
DISPLAY 0.787234 (-11970 4585);
PAINT MONO (-11970 4585);
FORCEPROP 2 LAST CDS_LIB pure_quanta
J 0
(-11975 4675);
DISPLAY INVISIBLE (-11975 4675);
FORCEPROP 1 LAST PATH I59
J 0
(-11925 4850);
DISPLAY 0.978723 (-11925 4850);
PAINT WHITE (-11925 4850);
DISPLAY INVISIBLE (-11925 4850);
FORCEPROP 0 LAST $SEC 1
J 0
(-11925 4850);
DISPLAY 0.680851 (-11925 4850);
PAINT MONO (-11925 4850);
DISPLAY INVISIBLE (-11925 4850);
FORCEPROP 0 LAST CDS_SEC 1
J 0
(-11925 4850);
DISPLAY 1.021277 (-11925 4850);
DISPLAY INVISIBLE (-11925 4850);
FORCEADD GND..1
(-16000 175);
FORCEPROP 3 LASTPIN (-16000 225) SIG_NAME GND\g
J 0
(-15990 235);
DISPLAY 0.659574 (-15990 235);
PAINT MONO (-15990 235);
DISPLAY INVISIBLE (-15990 235);
FORCEPROP 1 LAST HDL_POWER GND
J 0
(-16000 325);
DISPLAY 1.170213 (-16000 325);
PAINT GREEN (-16000 325);
DISPLAY INVISIBLE (-16000 325);
FORCEPROP 2 LAST CDS_LIB logical_power
J 0
(-16000 175);
DISPLAY INVISIBLE (-16000 175);
FORCEPROP 1 LAST SIZE 1B
J 0
(-15925 125);
DISPLAY 0.872340 (-15925 125);
PAINT AQUA (-15925 125);
DISPLAY INVISIBLE (-15925 125);
FORCEPROP 1 LAST PATH I6
J 0
(-15925 175);
DISPLAY 0.872340 (-15925 175);
PAINT AQUA (-15925 175);
DISPLAY INVISIBLE (-15925 175);
FORCEADD UNIVERSAL_GND..1
(-11700 1950);
FORCEPROP 3 LASTPIN (-11700 2000) SIG_NAME AGND_HSC\g
J 0
(-11690 2010);
DISPLAY 0.659574 (-11690 2010);
PAINT MONO (-11690 2010);
DISPLAY INVISIBLE (-11690 2010);
FORCEPROP 1 LAST HDL_POWER AGND_HSC
J 1
(-11675 1875);
DISPLAY 0.723404 (-11675 1875);
PAINT GREEN (-11675 1875);
FORCEPROP 2 LAST CDS_LIB logical_power
J 0
(-11700 1950);
DISPLAY INVISIBLE (-11700 1950);
FORCEPROP 1 LAST PATH I60
J 0
(-11625 1950);
DISPLAY 0.872340 (-11625 1950);
PAINT AQUA (-11625 1950);
DISPLAY INVISIBLE (-11625 1950);
FORCEADD Q_RES..2
(-11700 2150);
FORCEPROP 1 LAST PART_NUMBER CS26192FB03
J 0
(-11650 2075);
DISPLAY 0.723404 (-11650 2075);
PAINT WHITE (-11650 2075);
DISPLAY INVISIBLE (-11650 2075);
FORCEPROP 1 LAST WATTAGE 1/16W
J 0
(-11650 2175);
DISPLAY 0.723404 (-11650 2175);
PAINT SKYBLUE (-11650 2175);
FORCEPROP 1 LAST TOLERANCE 1%
J 0
(-11645 2225);
DISPLAY 0.723404 (-11645 2225);
PAINT SKYBLUE (-11645 2225);
FORCEPROP 2 LAST ROOM HSC1_BOM1
J 0
(-11625 2375);
DISPLAY 1.021277 (-11625 2375);
FORCEPROP 1 LAST PACK_TYPE 0402LF
J 0
(-11650 2025);
DISPLAY 0.723404 (-11650 2025);
PAINT SKYBLUE (-11650 2025);
FORCEPROP 1 LAST MATERIAL CHIP
J 0
(-11650 2125);
DISPLAY 0.723404 (-11650 2125);
PAINT SKYBLUE (-11650 2125);
FORCEPROP 1 LAST VALUE 6.19K
J 0
(-11645 2275);
DISPLAY 0.723404 (-11645 2275);
PAINT SKYBLUE (-11645 2275);
FORCEPROP 1 LAST LOCATION R1117
J 0
(-11645 2325);
DISPLAY 0.723404 (-11645 2325);
PAINT AQUA (-11645 2325);
FORCEPROP 1 LASTPIN (-11700 2250) $PN 1
J 0
(-11695 2212);
DISPLAY 0.787234 (-11695 2212);
PAINT MONO (-11695 2212);
FORCEPROP 1 LASTPIN (-11700 2050) $PN 2
J 0
(-11695 2060);
DISPLAY 0.787234 (-11695 2060);
PAINT MONO (-11695 2060);
FORCEPROP 2 LAST CDS_LIB pure_quanta
J 0
(-11700 2150);
DISPLAY INVISIBLE (-11700 2150);
FORCEPROP 1 LAST PATH I61
J 0
(-11650 2325);
DISPLAY 0.978723 (-11650 2325);
PAINT WHITE (-11650 2325);
DISPLAY INVISIBLE (-11650 2325);
FORCEPROP 0 LAST $SEC 1
J 0
(-11625 2375);
DISPLAY 0.680851 (-11625 2375);
PAINT MONO (-11625 2375);
DISPLAY INVISIBLE (-11625 2375);
FORCEPROP 0 LAST CDS_SEC 1
J 0
(-11625 2375);
DISPLAY 1.021277 (-11625 2375);
DISPLAY INVISIBLE (-11625 2375);
FORCEADD Q_RES..2
(-11700 2600);
FORCEPROP 1 LAST PART_NUMBER CS31692FB03
J 0
(-11660 2475);
DISPLAY 0.723404 (-11660 2475);
PAINT WHITE (-11660 2475);
DISPLAY INVISIBLE (-11660 2475);
FORCEPROP 2 LAST ROOM HSC1_BOM1
J 0
(-11650 2775);
DISPLAY 1.021277 (-11650 2775);
FORCEPROP 1 LAST WATTAGE 1/16W
J 0
(-11660 2575);
DISPLAY 0.723404 (-11660 2575);
PAINT SKYBLUE (-11660 2575);
FORCEPROP 1 LAST MATERIAL CHIP
J 0
(-11660 2525);
DISPLAY 0.723404 (-11660 2525);
PAINT SKYBLUE (-11660 2525);
FORCEPROP 1 LAST PACK_TYPE 0402LF
J 0
(-11660 2425);
DISPLAY 0.723404 (-11660 2425);
PAINT SKYBLUE (-11660 2425);
FORCEPROP 1 LAST TOLERANCE 1%
J 0
(-11655 2625);
DISPLAY 0.723404 (-11655 2625);
PAINT SKYBLUE (-11655 2625);
FORCEPROP 1 LAST VALUE 16.9K
J 0
(-11655 2675);
DISPLAY 0.723404 (-11655 2675);
PAINT SKYBLUE (-11655 2675);
FORCEPROP 1 LAST LOCATION R3933
J 0
(-11655 2725);
DISPLAY 0.723404 (-11655 2725);
PAINT AQUA (-11655 2725);
FORCEPROP 1 LASTPIN (-11700 2700) $PN 1
J 0
(-11695 2662);
DISPLAY 0.787234 (-11695 2662);
PAINT MONO (-11695 2662);
FORCEPROP 1 LASTPIN (-11700 2500) $PN 2
J 0
(-11695 2510);
DISPLAY 0.787234 (-11695 2510);
PAINT MONO (-11695 2510);
FORCEPROP 2 LAST CDS_LIB pure_quanta
J 0
(-11700 2600);
DISPLAY INVISIBLE (-11700 2600);
FORCEPROP 1 LAST PATH I62
J 0
(-11650 2775);
DISPLAY 0.978723 (-11650 2775);
PAINT WHITE (-11650 2775);
DISPLAY INVISIBLE (-11650 2775);
FORCEPROP 0 LAST $SEC 1
J 0
(-11650 2775);
DISPLAY 0.680851 (-11650 2775);
PAINT MONO (-11650 2775);
DISPLAY INVISIBLE (-11650 2775);
FORCEPROP 0 LAST CDS_SEC 1
J 0
(-11650 2775);
DISPLAY 1.021277 (-11650 2775);
DISPLAY INVISIBLE (-11650 2775);
FORCEADD OFFPAGE..5
R 2
(-11200 2400);
FORCEPROP 2 LAST $XR3 259 
J 0
(-10651 2400);
DISPLAY 0.638298 (-10651 2400);
PAINT MONO (-10651 2400);
FORCEPROP 2 LAST $XR2 247 
J 0
(-10771 2400);
DISPLAY 0.638298 (-10771 2400);
PAINT MONO (-10771 2400);
FORCEPROP 2 LAST $XR1 214 
J 0
(-10891 2400);
DISPLAY 0.638298 (-10891 2400);
PAINT MONO (-10891 2400);
FORCEPROP 2 LAST $XR0 305 
J 0
(-11011 2400);
DISPLAY 0.638298 (-11011 2400);
PAINT MONO (-11011 2400);
FORCEPROP 1 LAST COMMENT_BODY TRUE
J 2
(-11300 2325);
DISPLAY 1.170213 (-11300 2325);
PAINT GREEN (-11300 2325);
DISPLAY INVISIBLE (-11300 2325);
FORCEPROP 1 LAST OFFPAGE TRUE
J 2
(-11525 2275);
DISPLAY 0.872340 (-11525 2275);
PAINT AQUA (-11525 2275);
DISPLAY INVISIBLE (-11525 2275);
FORCEPROP 2 LAST CDS_LIB standard
J 0
(-11200 2400);
DISPLAY INVISIBLE (-11200 2400);
FORCEPROP 2 LAST PATH I63
J 0
(-10750 2450);
DISPLAY 1.021277 (-10750 2450);
DISPLAY INVISIBLE (-10750 2450);
FORCEADD UNIVERSAL_GND..1
(-11225 2700);
FORCEPROP 3 LASTPIN (-11225 2750) SIG_NAME AGND_HSC\g
J 0
(-11215 2760);
DISPLAY 0.659574 (-11215 2760);
PAINT MONO (-11215 2760);
DISPLAY INVISIBLE (-11215 2760);
FORCEPROP 1 LAST HDL_POWER AGND_HSC
J 1
(-11200 2625);
DISPLAY 0.723404 (-11200 2625);
PAINT GREEN (-11200 2625);
FORCEPROP 2 LAST CDS_LIB logical_power
J 0
(-11225 2700);
DISPLAY INVISIBLE (-11225 2700);
FORCEPROP 1 LAST PATH I64
J 0
(-11150 2700);
DISPLAY 0.872340 (-11150 2700);
PAINT AQUA (-11150 2700);
DISPLAY INVISIBLE (-11150 2700);
FORCEADD OFFPAGE..5
R 2
(-11875 2975);
FORCEPROP 2 LAST $XR1 303 
J 0
(-11566 2975);
DISPLAY 0.638298 (-11566 2975);
PAINT MONO (-11566 2975);
FORCEPROP 2 LAST $XR0 302 
J 0
(-11686 2975);
DISPLAY 0.638298 (-11686 2975);
PAINT MONO (-11686 2975);
FORCEPROP 1 LAST COMMENT_BODY TRUE
J 2
(-11975 2900);
DISPLAY 1.170213 (-11975 2900);
PAINT GREEN (-11975 2900);
DISPLAY INVISIBLE (-11975 2900);
FORCEPROP 1 LAST OFFPAGE TRUE
J 2
(-12200 2850);
DISPLAY 0.872340 (-12200 2850);
PAINT AQUA (-12200 2850);
DISPLAY INVISIBLE (-12200 2850);
FORCEPROP 2 LAST CDS_LIB standard
J 0
(-11875 2975);
DISPLAY INVISIBLE (-11875 2975);
FORCEPROP 2 LAST PATH I65
J 0
(-11550 3025);
DISPLAY 1.021277 (-11550 3025);
DISPLAY INVISIBLE (-11550 3025);
FORCEADD OFFPAGE..5
R 2
(-11875 3175);
FORCEPROP 2 LAST $XR1 303 
J 0
(-11566 3175);
DISPLAY 0.638298 (-11566 3175);
PAINT MONO (-11566 3175);
FORCEPROP 2 LAST $XR0 302 
J 0
(-11686 3175);
DISPLAY 0.638298 (-11686 3175);
PAINT MONO (-11686 3175);
FORCEPROP 1 LAST COMMENT_BODY TRUE
J 2
(-11975 3100);
DISPLAY 1.170213 (-11975 3100);
PAINT GREEN (-11975 3100);
DISPLAY INVISIBLE (-11975 3100);
FORCEPROP 1 LAST OFFPAGE TRUE
J 2
(-12200 3050);
DISPLAY 0.872340 (-12200 3050);
PAINT AQUA (-12200 3050);
DISPLAY INVISIBLE (-12200 3050);
FORCEPROP 2 LAST CDS_LIB standard
J 0
(-11875 3175);
DISPLAY INVISIBLE (-11875 3175);
FORCEPROP 2 LAST PATH I66
J 0
(-11550 3225);
DISPLAY 1.021277 (-11550 3225);
DISPLAY INVISIBLE (-11550 3225);
FORCEADD OFFPAGE..5
R 2
(-11875 3275);
FORCEPROP 2 LAST $XR1 303 
J 0
(-11566 3275);
DISPLAY 0.638298 (-11566 3275);
PAINT MONO (-11566 3275);
FORCEPROP 2 LAST $XR0 302 
J 0
(-11686 3275);
DISPLAY 0.638298 (-11686 3275);
PAINT MONO (-11686 3275);
FORCEPROP 1 LAST COMMENT_BODY TRUE
J 2
(-11975 3200);
DISPLAY 1.170213 (-11975 3200);
PAINT GREEN (-11975 3200);
DISPLAY INVISIBLE (-11975 3200);
FORCEPROP 1 LAST OFFPAGE TRUE
J 2
(-12200 3150);
DISPLAY 0.872340 (-12200 3150);
PAINT AQUA (-12200 3150);
DISPLAY INVISIBLE (-12200 3150);
FORCEPROP 2 LAST CDS_LIB standard
J 0
(-11875 3275);
DISPLAY INVISIBLE (-11875 3275);
FORCEPROP 2 LAST PATH I67
J 0
(-11550 3325);
DISPLAY 1.021277 (-11550 3325);
DISPLAY INVISIBLE (-11550 3325);
FORCEADD UNIVERSAL_POWER..1
(-11700 2800);
FORCEPROP 3 LASTPIN (-11700 2750) SIG_NAME P12V_AUX\g
J 0
(-11690 2760);
DISPLAY 0.659574 (-11690 2760);
PAINT MONO (-11690 2760);
DISPLAY INVISIBLE (-11690 2760);
FORCEPROP 1 LAST HDL_POWER P12V_AUX
J 1
(-11700 2850);
DISPLAY 0.723404 (-11700 2850);
PAINT GREEN (-11700 2850);
FORCEPROP 2 LAST BOM_COST MIO_VRD_SB
J 0
(-11700 2900);
DISPLAY 0.617021 (-11700 2900);
PAINT PURPLE (-11700 2900);
DISPLAY INVISIBLE (-11700 2900);
FORCEPROP 2 LAST CDS_LIB logical_power
J 0
(-11700 2800);
DISPLAY INVISIBLE (-11700 2800);
FORCEPROP 1 LAST PATH I68
J 0
(-11650 2825);
DISPLAY 0.872340 (-11650 2825);
PAINT AQUA (-11650 2825);
DISPLAY INVISIBLE (-11650 2825);
FORCEADD Q_CAP..1
(-11225 2875);
FORCEPROP 1 LAST PART_NUMBER CH3683K1B09
J 0
(-11150 2750);
DISPLAY 0.723404 (-11150 2750);
PAINT WHITE (-11150 2750);
DISPLAY INVISIBLE (-11150 2750);
FORCEPROP 2 LAST ROOM HSC1_BOM1
J 0
(-11150 3000);
DISPLAY 1.021277 (-11150 3000);
FORCEPROP 1 LAST PACK_TYPE 0402
J 0
(-11150 2700);
DISPLAY 0.723404 (-11150 2700);
PAINT SKYBLUE (-11150 2700);
FORCEPROP 1 LAST VALUE 0.068UF
J 0
(-11150 2900);
DISPLAY 0.723404 (-11150 2900);
PAINT SKYBLUE (-11150 2900);
FORCEPROP 1 LAST MATERIAL X7R
J 0
(-11150 2800);
DISPLAY 0.723404 (-11150 2800);
PAINT SKYBLUE (-11150 2800);
FORCEPROP 1 LAST VOLTAGE 16V
J 0
(-11150 2850);
DISPLAY 0.723404 (-11150 2850);
PAINT SKYBLUE (-11150 2850);
FORCEPROP 1 LAST LOCATION PC2191
J 0
(-11150 2950);
DISPLAY 0.723404 (-11150 2950);
PAINT AQUA (-11150 2950);
FORCEPROP 1 LASTPIN (-11225 2975) $PN 1
J 0
(-11215 2955);
DISPLAY 0.787234 (-11215 2955);
PAINT MONO (-11215 2955);
FORCEPROP 1 LASTPIN (-11225 2775) $PN 2
J 0
(-11215 2755);
DISPLAY 0.787234 (-11215 2755);
PAINT MONO (-11215 2755);
FORCEPROP 2 LAST CDS_LIB pure_quanta
J 0
(-11225 2875);
DISPLAY INVISIBLE (-11225 2875);
FORCEPROP 1 LAST TOLERANCE 10%
J 0
(-11175 2825);
DISPLAY 0.978723 (-11175 2825);
PAINT SKYBLUE (-11175 2825);
DISPLAY INVISIBLE (-11175 2825);
FORCEPROP 1 LAST PATH I69
J 0
(-11175 3025);
DISPLAY 0.978723 (-11175 3025);
PAINT WHITE (-11175 3025);
DISPLAY INVISIBLE (-11175 3025);
FORCEPROP 0 LAST $SEC 1
J 0
(-11150 3000);
DISPLAY 0.680851 (-11150 3000);
PAINT MONO (-11150 3000);
DISPLAY INVISIBLE (-11150 3000);
FORCEPROP 0 LAST CDS_SEC 1
J 0
(-11150 3000);
DISPLAY 1.021277 (-11150 3000);
DISPLAY INVISIBLE (-11150 3000);
FORCEADD Q_RES..2
(-15100 750);
FORCEPROP 1 LAST PART_NUMBER CS33162FB02
J 0
(-15060 625);
DISPLAY 0.723404 (-15060 625);
PAINT WHITE (-15060 625);
DISPLAY INVISIBLE (-15060 625);
FORCEPROP 1 LAST VALUE 31.6K
J 0
(-15055 825);
DISPLAY 0.723404 (-15055 825);
PAINT SKYBLUE (-15055 825);
FORCEPROP 1 LAST WATTAGE 1/16W
J 0
(-15060 725);
DISPLAY 0.723404 (-15060 725);
PAINT SKYBLUE (-15060 725);
FORCEPROP 1 LAST MATERIAL CHIP
J 0
(-15060 675);
DISPLAY 0.723404 (-15060 675);
PAINT SKYBLUE (-15060 675);
FORCEPROP 1 LAST PACK_TYPE 0402LF
J 0
(-15060 575);
DISPLAY 0.723404 (-15060 575);
PAINT SKYBLUE (-15060 575);
FORCEPROP 1 LAST TOLERANCE 1%
J 0
(-15055 775);
DISPLAY 0.723404 (-15055 775);
PAINT SKYBLUE (-15055 775);
FORCEPROP 1 LAST LOCATION R2585
J 0
(-15055 875);
DISPLAY 0.723404 (-15055 875);
PAINT AQUA (-15055 875);
FORCEPROP 2 LAST CDS_LIB pure_quanta
J 0
(-15100 750);
DISPLAY INVISIBLE (-15100 750);
FORCEPROP 1 LAST PATH I7
J 0
(-15050 925);
DISPLAY 0.978723 (-15050 925);
PAINT WHITE (-15050 925);
DISPLAY INVISIBLE (-15050 925);
FORCEPROP 0 LAST $SEC 1
J 0
(-15050 925);
DISPLAY INVISIBLE (-15050 925);
FORCEPROP 0 LAST CDS_SEC 1
J 0
(-15050 925);
DISPLAY INVISIBLE (-15050 925);
FORCEPROP 1 LASTPIN (-15100 850) $PN 1
J 0
(-15095 812);
DISPLAY 0.787234 (-15095 812);
PAINT MONO (-15095 812);
DISPLAY INVISIBLE (-15095 812);
FORCEPROP 1 LASTPIN (-15100 650) $PN 2
J 0
(-15095 660);
DISPLAY 0.787234 (-15095 660);
PAINT MONO (-15095 660);
DISPLAY INVISIBLE (-15095 660);
FORCEADD OFFPAGE..5
R 2
(-11100 3075);
FORCEPROP 2 LAST $XR1 303 
J 0
(-10791 3075);
DISPLAY 0.638298 (-10791 3075);
PAINT MONO (-10791 3075);
FORCEPROP 2 LAST $XR0 302 
J 0
(-10911 3075);
DISPLAY 0.638298 (-10911 3075);
PAINT MONO (-10911 3075);
FORCEPROP 1 LAST COMMENT_BODY TRUE
J 2
(-11200 3000);
DISPLAY 1.170213 (-11200 3000);
PAINT GREEN (-11200 3000);
DISPLAY INVISIBLE (-11200 3000);
FORCEPROP 1 LAST OFFPAGE TRUE
J 2
(-11425 2950);
DISPLAY 0.872340 (-11425 2950);
PAINT AQUA (-11425 2950);
DISPLAY INVISIBLE (-11425 2950);
FORCEPROP 2 LAST CDS_LIB standard
J 0
(-11100 3075);
DISPLAY INVISIBLE (-11100 3075);
FORCEPROP 2 LAST PATH I70
J 0
(-10775 3125);
DISPLAY 1.021277 (-10775 3125);
DISPLAY INVISIBLE (-10775 3125);
FORCEADD UNIVERSAL_GND..1
(-11350 3575);
FORCEPROP 3 LASTPIN (-11350 3625) SIG_NAME AGND_HSC\g
J 0
(-11340 3635);
DISPLAY 0.659574 (-11340 3635);
PAINT MONO (-11340 3635);
DISPLAY INVISIBLE (-11340 3635);
FORCEPROP 1 LAST HDL_POWER AGND_HSC
J 1
(-11325 3500);
DISPLAY 0.723404 (-11325 3500);
PAINT GREEN (-11325 3500);
FORCEPROP 2 LAST CDS_LIB logical_power
J 0
(-11350 3575);
DISPLAY INVISIBLE (-11350 3575);
FORCEPROP 1 LAST PATH I71
J 0
(-11275 3575);
DISPLAY 0.872340 (-11275 3575);
PAINT AQUA (-11275 3575);
DISPLAY INVISIBLE (-11275 3575);
FORCEADD OFFPAGE..4
(-11525 3975);
FORCEPROP 2 LAST $XR1 303 
J 0
(-11219 3975);
DISPLAY 0.638298 (-11219 3975);
PAINT MONO (-11219 3975);
FORCEPROP 2 LAST $XR0 302 
J 0
(-11339 3975);
DISPLAY 0.638298 (-11339 3975);
PAINT MONO (-11339 3975);
FORCEPROP 1 LAST COMMENT_BODY TRUE
J 0
(-11550 3875);
DISPLAY 0.872340 (-11550 3875);
PAINT GREEN (-11550 3875);
DISPLAY INVISIBLE (-11550 3875);
FORCEPROP 1 LAST OFFPAGE TRUE
J 0
(-11200 3850);
DISPLAY 0.872340 (-11200 3850);
PAINT GREEN (-11200 3850);
DISPLAY INVISIBLE (-11200 3850);
FORCEPROP 2 LAST CDS_LIB standard
J 0
(-11525 3975);
DISPLAY INVISIBLE (-11525 3975);
FORCEPROP 2 LAST PATH I72
J 0
(-11200 4025);
DISPLAY 1.021277 (-11200 4025);
DISPLAY INVISIBLE (-11200 4025);
FORCEADD OFFPAGE..4
(-11525 4175);
FORCEPROP 2 LAST $XR1 303 
J 0
(-11219 4175);
DISPLAY 0.638298 (-11219 4175);
PAINT MONO (-11219 4175);
FORCEPROP 2 LAST $XR0 302 
J 0
(-11339 4175);
DISPLAY 0.638298 (-11339 4175);
PAINT MONO (-11339 4175);
FORCEPROP 1 LAST COMMENT_BODY TRUE
J 0
(-11550 4075);
DISPLAY 0.872340 (-11550 4075);
PAINT GREEN (-11550 4075);
DISPLAY INVISIBLE (-11550 4075);
FORCEPROP 1 LAST OFFPAGE TRUE
J 0
(-11200 4050);
DISPLAY 0.872340 (-11200 4050);
PAINT GREEN (-11200 4050);
DISPLAY INVISIBLE (-11200 4050);
FORCEPROP 2 LAST CDS_LIB standard
J 0
(-11525 4175);
DISPLAY INVISIBLE (-11525 4175);
FORCEPROP 2 LAST PATH I73
J 0
(-11200 4225);
DISPLAY 1.021277 (-11200 4225);
DISPLAY INVISIBLE (-11200 4225);
FORCEADD UNIVERSAL_GND..1
(-11500 4375);
FORCEPROP 3 LASTPIN (-11500 4425) SIG_NAME AGND_HSC\g
J 0
(-11490 4435);
DISPLAY 0.659574 (-11490 4435);
PAINT MONO (-11490 4435);
DISPLAY INVISIBLE (-11490 4435);
FORCEPROP 1 LAST HDL_POWER AGND_HSC
J 1
(-11475 4300);
DISPLAY 0.723404 (-11475 4300);
PAINT GREEN (-11475 4300);
FORCEPROP 2 LAST CDS_LIB logical_power
J 0
(-11500 4375);
DISPLAY INVISIBLE (-11500 4375);
FORCEPROP 1 LAST PATH I74
J 0
(-11425 4375);
DISPLAY 0.872340 (-11425 4375);
PAINT AQUA (-11425 4375);
DISPLAY INVISIBLE (-11425 4375);
FORCEADD Q_CAP..1
(-11500 4675);
FORCEPROP 1 LAST PART_NUMBER CH31006KB18
J 0
(-11425 4575);
DISPLAY 0.723404 (-11425 4575);
PAINT WHITE (-11425 4575);
DISPLAY INVISIBLE (-11425 4575);
FORCEPROP 1 LAST VOLTAGE 50V
J 0
(-11425 4675);
DISPLAY 0.723404 (-11425 4675);
PAINT SKYBLUE (-11425 4675);
FORCEPROP 1 LAST PACK_TYPE C0402
J 0
(-11425 4525);
DISPLAY 0.723404 (-11425 4525);
PAINT SKYBLUE (-11425 4525);
FORCEPROP 1 LAST MATERIAL X7R
J 0
(-11425 4625);
DISPLAY 0.723404 (-11425 4625);
PAINT SKYBLUE (-11425 4625);
FORCEPROP 2 LAST ROOM HSC1_BOM1
J 0
(-11425 4825);
DISPLAY 1.021277 (-11425 4825);
FORCEPROP 1 LAST VALUE 0.01UF
J 0
(-11425 4725);
DISPLAY 0.723404 (-11425 4725);
PAINT SKYBLUE (-11425 4725);
FORCEPROP 1 LAST LOCATION PC2190
J 0
(-11425 4775);
DISPLAY 0.723404 (-11425 4775);
PAINT AQUA (-11425 4775);
FORCEPROP 1 LASTPIN (-11500 4775) $PN 1
J 0
(-11490 4755);
DISPLAY 0.787234 (-11490 4755);
PAINT MONO (-11490 4755);
FORCEPROP 1 LASTPIN (-11500 4575) $PN 2
J 0
(-11490 4555);
DISPLAY 0.787234 (-11490 4555);
PAINT MONO (-11490 4555);
FORCEPROP 1 LAST TOLERANCE 10%
J 0
(-11450 4625);
DISPLAY 0.978723 (-11450 4625);
PAINT SKYBLUE (-11450 4625);
DISPLAY INVISIBLE (-11450 4625);
FORCEPROP 2 LAST CDS_LIB pure_quanta
J 0
(-11500 4675);
DISPLAY INVISIBLE (-11500 4675);
FORCEPROP 1 LAST PATH I75
J 0
(-11450 4825);
DISPLAY 0.978723 (-11450 4825);
PAINT WHITE (-11450 4825);
DISPLAY INVISIBLE (-11450 4825);
FORCEPROP 0 LAST $SEC 1
J 0
(-11425 4825);
DISPLAY 0.680851 (-11425 4825);
PAINT MONO (-11425 4825);
DISPLAY INVISIBLE (-11425 4825);
FORCEPROP 0 LAST CDS_SEC 1
J 0
(-11425 4825);
DISPLAY 1.021277 (-11425 4825);
DISPLAY INVISIBLE (-11425 4825);
FORCEADD Q_CAP..1
(-10650 3125);
FORCEPROP 1 LAST PART_NUMBER CH30106KB19
J 0
(-10575 3075);
DISPLAY 0.723404 (-10575 3075);
PAINT WHITE (-10575 3075);
DISPLAY INVISIBLE (-10575 3075);
FORCEPROP 1 LAST VOLTAGE 50V
J 0
(-10575 3175);
DISPLAY 0.723404 (-10575 3175);
PAINT SKYBLUE (-10575 3175);
FORCEPROP 1 LAST MATERIAL X7R
J 0
(-10575 3125);
DISPLAY 0.723404 (-10575 3125);
PAINT SKYBLUE (-10575 3125);
FORCEPROP 2 LAST ROOM HSC1_BOM1
J 0
(-10575 3325);
DISPLAY 1.021277 (-10575 3325);
FORCEPROP 1 LAST PACK_TYPE C0402
J 0
(-10575 3025);
DISPLAY 0.723404 (-10575 3025);
PAINT SKYBLUE (-10575 3025);
FORCEPROP 1 LAST VALUE 0.001UF
J 0
(-10575 3225);
DISPLAY 0.723404 (-10575 3225);
PAINT SKYBLUE (-10575 3225);
FORCEPROP 1 LAST LOCATION PC2192
J 0
(-10575 3275);
DISPLAY 0.723404 (-10575 3275);
PAINT AQUA (-10575 3275);
FORCEPROP 1 LASTPIN (-10650 3225) $PN 1
J 0
(-10640 3205);
DISPLAY 0.787234 (-10640 3205);
PAINT MONO (-10640 3205);
FORCEPROP 1 LASTPIN (-10650 3025) $PN 2
J 0
(-10640 3005);
DISPLAY 0.787234 (-10640 3005);
PAINT MONO (-10640 3005);
FORCEPROP 2 LAST CDS_LIB pure_quanta
J 0
(-10650 3125);
DISPLAY INVISIBLE (-10650 3125);
FORCEPROP 1 LAST TOLERANCE 10%
J 0
(-10600 3075);
DISPLAY 0.978723 (-10600 3075);
PAINT SKYBLUE (-10600 3075);
DISPLAY INVISIBLE (-10600 3075);
FORCEPROP 1 LAST PATH I77
J 0
(-10600 3275);
DISPLAY 0.978723 (-10600 3275);
PAINT WHITE (-10600 3275);
DISPLAY INVISIBLE (-10600 3275);
FORCEPROP 0 LAST $SEC 1
J 0
(-10575 3325);
DISPLAY 0.680851 (-10575 3325);
PAINT MONO (-10575 3325);
DISPLAY INVISIBLE (-10575 3325);
FORCEPROP 0 LAST CDS_SEC 1
J 0
(-10575 3325);
DISPLAY 1.021277 (-10575 3325);
DISPLAY INVISIBLE (-10575 3325);
FORCEADD UNIVERSAL_GND..1
(-10350 2800);
FORCEPROP 3 LASTPIN (-10350 2850) SIG_NAME AGND_HSC\g
J 0
(-10340 2860);
DISPLAY 0.659574 (-10340 2860);
PAINT MONO (-10340 2860);
DISPLAY INVISIBLE (-10340 2860);
FORCEPROP 1 LAST HDL_POWER AGND_HSC
J 1
(-10325 2725);
DISPLAY 0.723404 (-10325 2725);
PAINT GREEN (-10325 2725);
FORCEPROP 2 LAST CDS_LIB logical_power
J 0
(-10350 2800);
DISPLAY INVISIBLE (-10350 2800);
FORCEPROP 1 LAST PATH I78
J 0
(-10275 2800);
DISPLAY 0.872340 (-10275 2800);
PAINT AQUA (-10275 2800);
DISPLAY INVISIBLE (-10275 2800);
FORCEADD Q_RES..2
(-10175 3150);
FORCEPROP 1 LAST PART_NUMBER CS31002FB08
J 0
(-10125 3050);
DISPLAY 0.723404 (-10125 3050);
PAINT WHITE (-10125 3050);
DISPLAY INVISIBLE (-10125 3050);
FORCEPROP 1 LAST PACK_TYPE 0402LF
J 0
(-10125 3000);
DISPLAY 0.723404 (-10125 3000);
PAINT SKYBLUE (-10125 3000);
FORCEPROP 1 LAST WATTAGE 1/16W
J 0
(-10125 3150);
DISPLAY 0.723404 (-10125 3150);
PAINT SKYBLUE (-10125 3150);
FORCEPROP 2 LAST ROOM HSC1_BOM1
J 0
(-10100 3350);
DISPLAY 1.021277 (-10100 3350);
FORCEPROP 1 LAST MATERIAL CHIP
J 0
(-10125 3100);
DISPLAY 0.723404 (-10125 3100);
PAINT SKYBLUE (-10125 3100);
FORCEPROP 1 LAST VALUE 10K
J 0
(-10120 3250);
DISPLAY 0.723404 (-10120 3250);
PAINT SKYBLUE (-10120 3250);
FORCEPROP 1 LAST TOLERANCE 1%
J 0
(-10120 3200);
DISPLAY 0.723404 (-10120 3200);
PAINT SKYBLUE (-10120 3200);
FORCEPROP 1 LAST LOCATION PR3935
J 0
(-10120 3300);
DISPLAY 0.723404 (-10120 3300);
PAINT AQUA (-10120 3300);
FORCEPROP 1 LASTPIN (-10175 3250) $PN 1
J 0
(-10170 3212);
DISPLAY 0.787234 (-10170 3212);
PAINT MONO (-10170 3212);
FORCEPROP 1 LASTPIN (-10175 3050) $PN 2
J 0
(-10170 3060);
DISPLAY 0.787234 (-10170 3060);
PAINT MONO (-10170 3060);
FORCEPROP 2 LAST CDS_LIB pure_quanta
J 0
(-10175 3150);
DISPLAY INVISIBLE (-10175 3150);
FORCEPROP 1 LAST PATH I79
J 0
(-10125 3325);
DISPLAY 0.978723 (-10125 3325);
PAINT WHITE (-10125 3325);
DISPLAY INVISIBLE (-10125 3325);
FORCEPROP 0 LAST $SEC 1
J 0
(-10100 3350);
DISPLAY 0.680851 (-10100 3350);
PAINT MONO (-10100 3350);
DISPLAY INVISIBLE (-10100 3350);
FORCEPROP 0 LAST CDS_SEC 1
J 0
(-10100 3350);
DISPLAY 1.021277 (-10100 3350);
DISPLAY INVISIBLE (-10100 3350);
FORCEADD GND..1
(-15100 500);
FORCEPROP 3 LASTPIN (-15100 550) SIG_NAME GND\g
J 0
(-15090 560);
DISPLAY 0.659574 (-15090 560);
PAINT MONO (-15090 560);
DISPLAY INVISIBLE (-15090 560);
FORCEPROP 1 LAST HDL_POWER GND
J 0
(-15100 650);
DISPLAY 1.170213 (-15100 650);
PAINT GREEN (-15100 650);
DISPLAY INVISIBLE (-15100 650);
FORCEPROP 2 LAST CDS_LIB logical_power
J 0
(-15100 500);
DISPLAY INVISIBLE (-15100 500);
FORCEPROP 1 LAST SIZE 1B
J 0
(-15025 450);
DISPLAY 0.872340 (-15025 450);
PAINT AQUA (-15025 450);
DISPLAY INVISIBLE (-15025 450);
FORCEPROP 1 LAST PATH I8
J 0
(-15025 500);
DISPLAY 0.872340 (-15025 500);
PAINT AQUA (-15025 500);
DISPLAY INVISIBLE (-15025 500);
FORCEADD OFFPAGE..4
(-10025 3375);
FORCEPROP 2 LAST $XR1 303 
J 0
(-9539 3375);
DISPLAY 0.638298 (-9539 3375);
PAINT MONO (-9539 3375);
FORCEPROP 2 LAST $XR0 302 
J 0
(-9659 3375);
DISPLAY 0.638298 (-9659 3375);
PAINT MONO (-9659 3375);
FORCEPROP 1 LAST COMMENT_BODY TRUE
J 0
(-10050 3275);
DISPLAY 0.872340 (-10050 3275);
PAINT GREEN (-10050 3275);
DISPLAY INVISIBLE (-10050 3275);
FORCEPROP 1 LAST OFFPAGE TRUE
J 0
(-9700 3250);
DISPLAY 0.872340 (-9700 3250);
PAINT GREEN (-9700 3250);
DISPLAY INVISIBLE (-9700 3250);
FORCEPROP 2 LAST CDS_LIB standard
J 2
(-10025 3375);
DISPLAY INVISIBLE (-10025 3375);
FORCEPROP 2 LAST PATH I80
J 0
(-9700 3425);
DISPLAY 1.021277 (-9700 3425);
DISPLAY INVISIBLE (-9700 3425);
FORCEADD Q_RES..1
(-10675 4275);
FORCEPROP 1 LAST PART_NUMBER CS02202FB02
J 0
(-10550 4300);
DISPLAY 0.723404 (-10550 4300);
PAINT WHITE (-10550 4300);
DISPLAY INVISIBLE (-10550 4300);
FORCEPROP 1 LAST VALUE 22
J 2
(-10750 4225);
DISPLAY 0.723404 (-10750 4225);
PAINT SKYBLUE (-10750 4225);
FORCEPROP 2 LAST ROOM HSC1_BOM1
J 0
(-10550 4350);
DISPLAY 1.021277 (-10550 4350);
FORCEPROP 1 LAST MATERIAL CHIP
J 0
(-10700 4175);
DISPLAY 0.723404 (-10700 4175);
PAINT SKYBLUE (-10700 4175);
FORCEPROP 1 LAST PACK_TYPE 0402LF
J 0
(-10500 4175);
DISPLAY 0.723404 (-10500 4175);
PAINT SKYBLUE (-10500 4175);
FORCEPROP 1 LAST WATTAGE 1/16W
J 2
(-10725 4175);
DISPLAY 0.723404 (-10725 4175);
PAINT SKYBLUE (-10725 4175);
FORCEPROP 1 LAST TOLERANCE 1%
J 0
(-10575 4225);
DISPLAY 0.723404 (-10575 4225);
PAINT SKYBLUE (-10575 4225);
FORCEPROP 1 LAST LOCATION R2588
J 0
(-10950 4300);
DISPLAY 0.723404 (-10950 4300);
PAINT AQUA (-10950 4300);
FORCEPROP 1 LASTPIN (-10775 4275) $PN 1
J 0
(-10763 4287);
DISPLAY 0.787234 (-10763 4287);
PAINT MONO (-10763 4287);
FORCEPROP 1 LASTPIN (-10575 4275) $PN 2
J 0
(-10613 4287);
DISPLAY 0.787234 (-10613 4287);
PAINT MONO (-10613 4287);
FORCEPROP 2 LAST CDS_LIB pure_quanta
J 0
(-10675 4275);
DISPLAY INVISIBLE (-10675 4275);
FORCEPROP 1 LAST PATH I81
J 0
(-10725 4425);
DISPLAY 0.978723 (-10725 4425);
PAINT WHITE (-10725 4425);
DISPLAY INVISIBLE (-10725 4425);
FORCEPROP 0 LAST $SEC 1
J 0
(-10625 4350);
DISPLAY 0.680851 (-10625 4350);
PAINT MONO (-10625 4350);
DISPLAY INVISIBLE (-10625 4350);
FORCEPROP 0 LAST CDS_SEC 1
J 0
(-10625 4350);
DISPLAY 1.021277 (-10625 4350);
DISPLAY INVISIBLE (-10625 4350);
FORCEADD Q_RES..1
(-10675 4100);
FORCEPROP 1 LAST PART_NUMBER CS02202FB02
J 0
(-10550 4125);
DISPLAY 0.723404 (-10550 4125);
PAINT WHITE (-10550 4125);
DISPLAY INVISIBLE (-10550 4125);
FORCEPROP 1 LAST WATTAGE 1/16W
J 2
(-10725 4000);
DISPLAY 0.723404 (-10725 4000);
PAINT SKYBLUE (-10725 4000);
FORCEPROP 1 LAST PACK_TYPE 0402LF
J 0
(-10500 4000);
DISPLAY 0.723404 (-10500 4000);
PAINT SKYBLUE (-10500 4000);
FORCEPROP 2 LAST ROOM HSC1_BOM1
J 0
(-10550 4175);
DISPLAY 1.021277 (-10550 4175);
FORCEPROP 1 LAST MATERIAL CHIP
J 0
(-10700 4000);
DISPLAY 0.723404 (-10700 4000);
PAINT SKYBLUE (-10700 4000);
FORCEPROP 1 LAST TOLERANCE 1%
J 0
(-10575 4050);
DISPLAY 0.723404 (-10575 4050);
PAINT SKYBLUE (-10575 4050);
FORCEPROP 1 LAST VALUE 22
J 2
(-10750 4050);
DISPLAY 0.723404 (-10750 4050);
PAINT SKYBLUE (-10750 4050);
FORCEPROP 1 LAST LOCATION R3934
J 0
(-10950 4125);
DISPLAY 0.723404 (-10950 4125);
PAINT AQUA (-10950 4125);
FORCEPROP 1 LASTPIN (-10775 4100) $PN 1
J 0
(-10763 4112);
DISPLAY 0.787234 (-10763 4112);
PAINT MONO (-10763 4112);
FORCEPROP 1 LASTPIN (-10575 4100) $PN 2
J 0
(-10613 4112);
DISPLAY 0.787234 (-10613 4112);
PAINT MONO (-10613 4112);
FORCEPROP 2 LAST CDS_LIB pure_quanta
J 0
(-10675 4100);
DISPLAY INVISIBLE (-10675 4100);
FORCEPROP 1 LAST PATH I82
J 0
(-10725 4250);
DISPLAY 0.978723 (-10725 4250);
PAINT WHITE (-10725 4250);
DISPLAY INVISIBLE (-10725 4250);
FORCEPROP 0 LAST $SEC 1
J 0
(-10625 4175);
DISPLAY 0.680851 (-10625 4175);
PAINT MONO (-10625 4175);
DISPLAY INVISIBLE (-10625 4175);
FORCEPROP 0 LAST CDS_SEC 1
J 0
(-10625 4175);
DISPLAY 1.021277 (-10625 4175);
DISPLAY INVISIBLE (-10625 4175);
FORCEADD Q_RES..1
(-9850 3975);
FORCEPROP 1 LAST PART_NUMBER CS41202FB05
J 0
(-9700 4000);
DISPLAY 0.723404 (-9700 4000);
PAINT WHITE (-9700 4000);
DISPLAY INVISIBLE (-9700 4000);
FORCEPROP 2 LAST ROOM HSC1_BOM1
J 0
(-9700 4050);
DISPLAY 1.021277 (-9700 4050);
FORCEPROP 1 LAST MATERIAL CHIP
J 0
(-9900 3875);
DISPLAY 0.723404 (-9900 3875);
PAINT SKYBLUE (-9900 3875);
FORCEPROP 1 LAST TOLERANCE 1%
J 0
(-9750 3925);
DISPLAY 0.723404 (-9750 3925);
PAINT SKYBLUE (-9750 3925);
FORCEPROP 1 LAST PACK_TYPE 0402LF
J 0
(-9700 3875);
DISPLAY 0.723404 (-9700 3875);
PAINT SKYBLUE (-9700 3875);
FORCEPROP 1 LAST WATTAGE 1/16W
J 2
(-9950 3875);
DISPLAY 0.723404 (-9950 3875);
PAINT SKYBLUE (-9950 3875);
FORCEPROP 1 LAST VALUE 120K
J 2
(-9900 3925);
DISPLAY 0.723404 (-9900 3925);
PAINT SKYBLUE (-9900 3925);
FORCEPROP 1 LAST LOCATION PR3937
J 0
(-10150 4000);
DISPLAY 0.723404 (-10150 4000);
PAINT AQUA (-10150 4000);
FORCEPROP 1 LASTPIN (-9950 3975) $PN 1
J 0
(-9938 3987);
DISPLAY 0.787234 (-9938 3987);
PAINT MONO (-9938 3987);
FORCEPROP 1 LASTPIN (-9750 3975) $PN 2
J 0
(-9788 3987);
DISPLAY 0.787234 (-9788 3987);
PAINT MONO (-9788 3987);
FORCEPROP 2 LAST CDS_LIB pure_quanta
J 0
(-9850 3975);
DISPLAY INVISIBLE (-9850 3975);
FORCEPROP 1 LAST PATH I84
J 0
(-9900 4125);
DISPLAY 0.978723 (-9900 4125);
PAINT WHITE (-9900 4125);
DISPLAY INVISIBLE (-9900 4125);
FORCEPROP 0 LAST $SEC 1
J 0
(-9800 4050);
DISPLAY 0.680851 (-9800 4050);
PAINT MONO (-9800 4050);
DISPLAY INVISIBLE (-9800 4050);
FORCEPROP 0 LAST CDS_SEC 1
J 0
(-9800 4050);
DISPLAY 1.021277 (-9800 4050);
DISPLAY INVISIBLE (-9800 4050);
FORCEADD Q_RES..2
(-10150 4600);
FORCEPROP 1 LAST PART_NUMBER CS24702FB06
J 0
(-10110 4475);
DISPLAY 0.723404 (-10110 4475);
PAINT WHITE (-10110 4475);
DISPLAY INVISIBLE (-10110 4475);
FORCEPROP 2 LAST ROOM HSC1_BOM1
J 0
(-10100 4775);
DISPLAY 1.021277 (-10100 4775);
FORCEPROP 1 LAST PACK_TYPE 0402LF
J 0
(-10110 4425);
DISPLAY 0.723404 (-10110 4425);
PAINT SKYBLUE (-10110 4425);
FORCEPROP 1 LAST WATTAGE 1/16W
J 0
(-10110 4575);
DISPLAY 0.723404 (-10110 4575);
PAINT SKYBLUE (-10110 4575);
FORCEPROP 1 LAST TOLERANCE 1%
J 0
(-10105 4625);
DISPLAY 0.723404 (-10105 4625);
PAINT SKYBLUE (-10105 4625);
FORCEPROP 1 LAST VALUE 4.7K
J 0
(-10105 4675);
DISPLAY 0.723404 (-10105 4675);
PAINT SKYBLUE (-10105 4675);
FORCEPROP 1 LAST MATERIAL CHIP
J 0
(-10110 4525);
DISPLAY 0.723404 (-10110 4525);
PAINT SKYBLUE (-10110 4525);
FORCEPROP 1 LAST LOCATION R3936
J 0
(-10105 4725);
DISPLAY 0.723404 (-10105 4725);
PAINT AQUA (-10105 4725);
FORCEPROP 1 LASTPIN (-10150 4700) $PN 1
J 0
(-10145 4662);
DISPLAY 0.787234 (-10145 4662);
PAINT MONO (-10145 4662);
FORCEPROP 1 LASTPIN (-10150 4500) $PN 2
J 0
(-10145 4510);
DISPLAY 0.787234 (-10145 4510);
PAINT MONO (-10145 4510);
FORCEPROP 2 LAST CDS_LIB pure_quanta
J 0
(-10150 4600);
DISPLAY INVISIBLE (-10150 4600);
FORCEPROP 1 LAST PATH I85
J 0
(-10100 4775);
DISPLAY 0.978723 (-10100 4775);
PAINT WHITE (-10100 4775);
DISPLAY INVISIBLE (-10100 4775);
FORCEPROP 0 LAST $SEC 1
J 0
(-10100 4775);
DISPLAY 0.680851 (-10100 4775);
PAINT MONO (-10100 4775);
DISPLAY INVISIBLE (-10100 4775);
FORCEPROP 0 LAST CDS_SEC 1
J 0
(-10100 4775);
DISPLAY 1.021277 (-10100 4775);
DISPLAY INVISIBLE (-10100 4775);
FORCEADD Q_RES..2
(-12050 5125);
FORCEPROP 1 LAST PART_NUMBER CS37502BB01
J 0
(-12010 5000);
DISPLAY 0.787234 (-12010 5000);
DISPLAY INVISIBLE (-12010 5000);
FORCEPROP 1 LAST PACK_TYPE 0402LF
J 0
(-12010 4950);
DISPLAY 0.787234 (-12010 4950);
FORCEPROP 2 LAST ROOM HSC1_BOM1
J 0
(-12000 5300);
DISPLAY 1.021277 (-12000 5300);
FORCEPROP 1 LAST VALUE 75K
J 0
(-12005 5200);
DISPLAY 0.787234 (-12005 5200);
FORCEPROP 1 LAST WATTAGE 1/16W
J 0
(-12010 5100);
DISPLAY 0.787234 (-12010 5100);
FORCEPROP 1 LAST MATERIAL CHIP
J 0
(-12010 5050);
DISPLAY 0.787234 (-12010 5050);
FORCEPROP 1 LAST TOLERANCE 0.1%
J 0
(-12005 5150);
DISPLAY 0.787234 (-12005 5150);
FORCEPROP 1 LAST LOCATION PR3931
J 0
(-12005 5250);
DISPLAY 0.978723 (-12005 5250);
FORCEPROP 1 LASTPIN (-12050 5225) $PN 1
J 0
(-12045 5187);
DISPLAY 0.787234 (-12045 5187);
PAINT MONO (-12045 5187);
FORCEPROP 1 LASTPIN (-12050 5025) $PN 2
J 0
(-12045 5035);
DISPLAY 0.787234 (-12045 5035);
PAINT MONO (-12045 5035);
FORCEPROP 2 LAST CDS_LIB pure_quanta
J 0
(-12050 5125);
DISPLAY INVISIBLE (-12050 5125);
FORCEPROP 1 LAST PATH I86
J 0
(-12000 5300);
DISPLAY 0.978723 (-12000 5300);
PAINT WHITE (-12000 5300);
DISPLAY INVISIBLE (-12000 5300);
FORCEPROP 0 LAST $SEC 1
J 0
(-12000 5300);
DISPLAY 0.680851 (-12000 5300);
PAINT MONO (-12000 5300);
DISPLAY INVISIBLE (-12000 5300);
FORCEPROP 0 LAST CDS_SEC 1
J 0
(-12000 5300);
DISPLAY 1.021277 (-12000 5300);
DISPLAY INVISIBLE (-12000 5300);
FORCEADD UNIVERSAL_POWER..1
(-9950 4950);
FORCEPROP 3 LASTPIN (-9950 4900) SIG_NAME HSC_VDD\g
J 0
(-9940 4910);
DISPLAY 0.659574 (-9940 4910);
PAINT MONO (-9940 4910);
DISPLAY INVISIBLE (-9940 4910);
FORCEPROP 1 LAST HDL_POWER HSC_VDD
J 1
(-9950 5000);
DISPLAY 0.723404 (-9950 5000);
PAINT GREEN (-9950 5000);
FORCEPROP 2 LAST BOM_COST MIO_VRD_SB
J 0
(-9950 5050);
DISPLAY 0.617021 (-9950 5050);
PAINT PURPLE (-9950 5050);
DISPLAY INVISIBLE (-9950 5050);
FORCEPROP 2 LAST CDS_LIB logical_power
J 0
(-9950 4950);
DISPLAY INVISIBLE (-9950 4950);
FORCEPROP 1 LAST PATH I87
J 0
(-9900 4975);
DISPLAY 0.872340 (-9900 4975);
PAINT AQUA (-9900 4975);
DISPLAY INVISIBLE (-9900 4975);
FORCEADD UNIVERSAL_POWER..1
(-10300 5500);
FORCEPROP 3 LASTPIN (-10300 5450) SIG_NAME P12V_AUX\g
J 0
(-10290 5460);
DISPLAY 0.659574 (-10290 5460);
PAINT MONO (-10290 5460);
DISPLAY INVISIBLE (-10290 5460);
FORCEPROP 1 LAST HDL_POWER P12V_AUX
J 1
(-10300 5550);
DISPLAY 0.723404 (-10300 5550);
PAINT GREEN (-10300 5550);
FORCEPROP 2 LAST CDS_LIB logical_power
J 0
(-10300 5500);
DISPLAY INVISIBLE (-10300 5500);
FORCEPROP 2 LAST BOM_COST MIO_VRD_SB
J 0
(-10300 5600);
DISPLAY 0.617021 (-10300 5600);
PAINT PURPLE (-10300 5600);
DISPLAY INVISIBLE (-10300 5600);
FORCEPROP 1 LAST PATH I88
J 0
(-10250 5525);
DISPLAY 0.872340 (-10250 5525);
PAINT AQUA (-10250 5525);
DISPLAY INVISIBLE (-10250 5525);
FORCEADD Q_CAP..1
(-9825 3550);
FORCEPROP 1 LAST PART_NUMBER CH3474K1B04
J 0
(-9750 3500);
DISPLAY 0.723404 (-9750 3500);
PAINT WHITE (-9750 3500);
DISPLAY INVISIBLE (-9750 3500);
FORCEPROP 2 LAST ROOM HSC1_BOM1
J 0
(-9750 3750);
DISPLAY 1.021277 (-9750 3750);
FORCEPROP 1 LAST MATERIAL X7R
J 0
(-9750 3550);
DISPLAY 0.723404 (-9750 3550);
PAINT SKYBLUE (-9750 3550);
FORCEPROP 1 LAST VOLTAGE 25V
J 0
(-9750 3600);
DISPLAY 0.723404 (-9750 3600);
PAINT SKYBLUE (-9750 3600);
FORCEPROP 1 LAST VALUE 0.047UF
J 0
(-9750 3650);
DISPLAY 0.723404 (-9750 3650);
PAINT SKYBLUE (-9750 3650);
FORCEPROP 1 LAST PACK_TYPE C0402
J 0
(-9750 3450);
DISPLAY 0.723404 (-9750 3450);
PAINT SKYBLUE (-9750 3450);
FORCEPROP 1 LAST LOCATION PC2193
J 0
(-9750 3700);
DISPLAY 0.723404 (-9750 3700);
PAINT AQUA (-9750 3700);
FORCEPROP 1 LASTPIN (-9825 3650) $PN 1
J 0
(-9815 3630);
DISPLAY 0.787234 (-9815 3630);
PAINT MONO (-9815 3630);
FORCEPROP 1 LASTPIN (-9825 3450) $PN 2
J 0
(-9815 3430);
DISPLAY 0.787234 (-9815 3430);
PAINT MONO (-9815 3430);
FORCEPROP 1 LAST TOLERANCE 10%
J 0
(-9775 3500);
DISPLAY 0.978723 (-9775 3500);
PAINT SKYBLUE (-9775 3500);
DISPLAY INVISIBLE (-9775 3500);
FORCEPROP 2 LAST CDS_LIB pure_quanta
J 0
(-9825 3550);
DISPLAY INVISIBLE (-9825 3550);
FORCEPROP 1 LAST PATH I89
J 0
(-9775 3700);
DISPLAY 0.978723 (-9775 3700);
PAINT WHITE (-9775 3700);
DISPLAY INVISIBLE (-9775 3700);
FORCEPROP 0 LAST $SEC 1
J 0
(-9750 3750);
DISPLAY 0.680851 (-9750 3750);
PAINT MONO (-9750 3750);
DISPLAY INVISIBLE (-9750 3750);
FORCEPROP 0 LAST CDS_SEC 1
J 0
(-9750 3750);
DISPLAY 1.021277 (-9750 3750);
DISPLAY INVISIBLE (-9750 3750);
FORCEADD UNIVERSAL_GND..1
(-14475 500);
FORCEPROP 3 LASTPIN (-14475 550) SIG_NAME AGND_HSC\g
J 0
(-14465 560);
DISPLAY 0.659574 (-14465 560);
PAINT MONO (-14465 560);
DISPLAY INVISIBLE (-14465 560);
FORCEPROP 1 LAST HDL_POWER AGND_HSC
J 1
(-14450 425);
DISPLAY 0.723404 (-14450 425);
PAINT GREEN (-14450 425);
FORCEPROP 2 LAST CDS_LIB logical_power
J 0
(-14475 500);
DISPLAY INVISIBLE (-14475 500);
FORCEPROP 1 LAST PATH I9
J 0
(-14400 500);
DISPLAY 0.872340 (-14400 500);
PAINT AQUA (-14400 500);
DISPLAY INVISIBLE (-14400 500);
FORCEADD UNIVERSAL_GND..1
(-9350 3300);
FORCEPROP 3 LASTPIN (-9350 3350) SIG_NAME AGND_HSC\g
J 0
(-9340 3360);
DISPLAY 0.659574 (-9340 3360);
PAINT MONO (-9340 3360);
DISPLAY INVISIBLE (-9340 3360);
FORCEPROP 1 LAST HDL_POWER AGND_HSC
J 1
(-9325 3225);
DISPLAY 0.723404 (-9325 3225);
PAINT GREEN (-9325 3225);
FORCEPROP 2 LAST CDS_LIB logical_power
J 0
(-9350 3300);
DISPLAY INVISIBLE (-9350 3300);
FORCEPROP 1 LAST PATH I90
J 0
(-9275 3300);
DISPLAY 0.872340 (-9275 3300);
PAINT AQUA (-9275 3300);
DISPLAY INVISIBLE (-9275 3300);
FORCEADD Q_RES..2
(-9350 3575);
FORCEPROP 1 LAST PART_NUMBER CS22002BB07
J 0
(-9300 3475);
DISPLAY 0.723404 (-9300 3475);
PAINT WHITE (-9300 3475);
DISPLAY INVISIBLE (-9300 3475);
FORCEPROP 2 LAST ROOM HSC1_BOM1
J 0
(-9275 3775);
DISPLAY 1.021277 (-9275 3775);
FORCEPROP 1 LAST MATERIAL CHIP
J 0
(-9300 3525);
DISPLAY 0.723404 (-9300 3525);
PAINT SKYBLUE (-9300 3525);
FORCEPROP 1 LAST WATTAGE 1/16W
J 0
(-9300 3575);
DISPLAY 0.723404 (-9300 3575);
PAINT SKYBLUE (-9300 3575);
FORCEPROP 1 LAST TOLERANCE 0.1%
J 0
(-9295 3625);
DISPLAY 0.723404 (-9295 3625);
PAINT SKYBLUE (-9295 3625);
FORCEPROP 1 LAST VALUE 2K
J 0
(-9295 3675);
DISPLAY 0.723404 (-9295 3675);
PAINT SKYBLUE (-9295 3675);
FORCEPROP 1 LAST PACK_TYPE 0402LF
J 0
(-9300 3425);
DISPLAY 0.723404 (-9300 3425);
PAINT SKYBLUE (-9300 3425);
FORCEPROP 1 LAST $LOCATION PR1133
J 0
(-9295 3725);
DISPLAY 0.723404 (-9295 3725);
PAINT AQUA (-9295 3725);
FORCEPROP 1 LASTPIN (-9350 3675) $PN 1
J 0
(-9345 3637);
DISPLAY 0.787234 (-9345 3637);
PAINT MONO (-9345 3637);
FORCEPROP 1 LASTPIN (-9350 3475) $PN 2
J 0
(-9345 3485);
DISPLAY 0.787234 (-9345 3485);
PAINT MONO (-9345 3485);
FORCEPROP 2 LAST CDS_LIB pure_quanta
J 0
(-9350 3575);
DISPLAY INVISIBLE (-9350 3575);
FORCEPROP 1 LAST PATH I91
J 0
(-9300 3750);
DISPLAY 0.978723 (-9300 3750);
PAINT WHITE (-9300 3750);
DISPLAY INVISIBLE (-9300 3750);
FORCEPROP 0 LAST CDS_LOCATION PR1133
J 0
(-9275 3775);
DISPLAY 1.021277 (-9275 3775);
DISPLAY INVISIBLE (-9275 3775);
FORCEPROP 0 LAST $SEC 1
J 0
(-9275 3775);
DISPLAY 0.680851 (-9275 3775);
PAINT MONO (-9275 3775);
DISPLAY INVISIBLE (-9275 3775);
FORCEPROP 0 LAST CDS_SEC 1
J 0
(-9275 3775);
DISPLAY 1.021277 (-9275 3775);
DISPLAY INVISIBLE (-9275 3775);
FORCEADD OFFPAGE..4
(-9100 3775);
FORCEPROP 2 LAST $XR1 303 
J 0
(-8824 3739);
DISPLAY 0.638298 (-8824 3739);
PAINT MONO (-8824 3739);
FORCEPROP 2 LAST $XR0 302 
J 0
(-8824 3775);
DISPLAY 0.638298 (-8824 3775);
PAINT MONO (-8824 3775);
FORCEPROP 1 LAST COMMENT_BODY TRUE
J 0
(-9125 3675);
DISPLAY 0.872340 (-9125 3675);
PAINT GREEN (-9125 3675);
DISPLAY INVISIBLE (-9125 3675);
FORCEPROP 1 LAST OFFPAGE TRUE
J 0
(-8775 3650);
DISPLAY 0.872340 (-8775 3650);
PAINT GREEN (-8775 3650);
DISPLAY INVISIBLE (-8775 3650);
FORCEPROP 2 LAST CDS_LIB standard
J 0
(-9100 3775);
DISPLAY INVISIBLE (-9100 3775);
FORCEPROP 2 LAST PATH I92
J 0
(-8775 3825);
DISPLAY 1.021277 (-8775 3825);
DISPLAY INVISIBLE (-8775 3825);
FORCEADD Q_RES..2
(-9725 4600);
FORCEPROP 1 LAST PART_NUMBER CS24702FB06
J 0
(-9685 4475);
DISPLAY 0.723404 (-9685 4475);
PAINT WHITE (-9685 4475);
DISPLAY INVISIBLE (-9685 4475);
FORCEPROP 2 LAST ROOM HSC1_BOM1
J 0
(-9675 4775);
DISPLAY 1.021277 (-9675 4775);
FORCEPROP 1 LAST WATTAGE 1/16W
J 0
(-9685 4575);
DISPLAY 0.723404 (-9685 4575);
PAINT SKYBLUE (-9685 4575);
FORCEPROP 1 LAST MATERIAL CHIP
J 0
(-9685 4525);
DISPLAY 0.723404 (-9685 4525);
PAINT SKYBLUE (-9685 4525);
FORCEPROP 1 LAST TOLERANCE 1%
J 0
(-9680 4625);
DISPLAY 0.723404 (-9680 4625);
PAINT SKYBLUE (-9680 4625);
FORCEPROP 1 LAST PACK_TYPE 0402LF
J 0
(-9685 4425);
DISPLAY 0.723404 (-9685 4425);
PAINT SKYBLUE (-9685 4425);
FORCEPROP 1 LAST VALUE 4.7K
J 0
(-9680 4675);
DISPLAY 0.723404 (-9680 4675);
PAINT SKYBLUE (-9680 4675);
FORCEPROP 1 LAST LOCATION R2587
J 0
(-9680 4725);
DISPLAY 0.723404 (-9680 4725);
PAINT AQUA (-9680 4725);
FORCEPROP 1 LASTPIN (-9725 4700) $PN 1
J 0
(-9720 4662);
DISPLAY 0.787234 (-9720 4662);
PAINT MONO (-9720 4662);
FORCEPROP 1 LASTPIN (-9725 4500) $PN 2
J 0
(-9720 4510);
DISPLAY 0.787234 (-9720 4510);
PAINT MONO (-9720 4510);
FORCEPROP 2 LAST CDS_LIB pure_quanta
J 0
(-9725 4600);
DISPLAY INVISIBLE (-9725 4600);
FORCEPROP 1 LAST PATH I93
J 0
(-9675 4775);
DISPLAY 0.978723 (-9675 4775);
PAINT WHITE (-9675 4775);
DISPLAY INVISIBLE (-9675 4775);
FORCEPROP 0 LAST $SEC 1
J 0
(-9675 4775);
DISPLAY 0.680851 (-9675 4775);
PAINT MONO (-9675 4775);
DISPLAY INVISIBLE (-9675 4775);
FORCEPROP 0 LAST CDS_SEC 1
J 0
(-9675 4775);
DISPLAY 1.021277 (-9675 4775);
DISPLAY INVISIBLE (-9675 4775);
FORCEADD UNIVERSAL_GND..1
(-9275 3900);
FORCEPROP 3 LASTPIN (-9275 3950) SIG_NAME AGND_HSC\g
J 0
(-9265 3960);
DISPLAY 0.659574 (-9265 3960);
PAINT MONO (-9265 3960);
DISPLAY INVISIBLE (-9265 3960);
FORCEPROP 1 LAST HDL_POWER AGND_HSC
J 1
(-9250 3850);
DISPLAY 0.723404 (-9250 3850);
PAINT GREEN (-9250 3850);
FORCEPROP 2 LAST CDS_LIB logical_power
J 0
(-9275 3900);
DISPLAY INVISIBLE (-9275 3900);
FORCEPROP 1 LAST PATH I94
J 0
(-9200 3900);
DISPLAY 0.872340 (-9200 3900);
PAINT AQUA (-9200 3900);
DISPLAY INVISIBLE (-9200 3900);
FORCEADD OFFPAGE..5
R 2
(-9100 4100);
FORCEPROP 2 LAST $XR1 215 
J 0
(-8791 4100);
DISPLAY 0.638298 (-8791 4100);
PAINT MONO (-8791 4100);
FORCEPROP 2 LAST $XR0 306 
J 0
(-8911 4100);
DISPLAY 0.638298 (-8911 4100);
PAINT MONO (-8911 4100);
FORCEPROP 1 LAST COMMENT_BODY TRUE
J 2
(-9200 4025);
DISPLAY 1.170213 (-9200 4025);
PAINT GREEN (-9200 4025);
DISPLAY INVISIBLE (-9200 4025);
FORCEPROP 1 LAST OFFPAGE TRUE
J 2
(-9425 3975);
DISPLAY 0.872340 (-9425 3975);
PAINT AQUA (-9425 3975);
DISPLAY INVISIBLE (-9425 3975);
FORCEPROP 2 LAST CDS_LIB standard
J 0
(-9100 4100);
DISPLAY INVISIBLE (-9100 4100);
FORCEPROP 2 LAST PATH I95
J 0
(-8900 4150);
DISPLAY 1.021277 (-8900 4150);
DISPLAY INVISIBLE (-8900 4150);
FORCEADD OFFPAGE..5
R 2
(-9100 4275);
PAINT RED (-9100 4275);
FORCEPROP 2 LAST $XR1 213 
J 0
(-8791 4275);
DISPLAY 0.638298 (-8791 4275);
PAINT MONO (-8791 4275);
FORCEPROP 2 LAST $XR0 305 
J 0
(-8911 4275);
DISPLAY 0.638298 (-8911 4275);
PAINT MONO (-8911 4275);
FORCEPROP 1 LAST COMMENT_BODY TRUE
J 2
(-9200 4200);
DISPLAY 1.170213 (-9200 4200);
PAINT GREEN (-9200 4200);
DISPLAY INVISIBLE (-9200 4200);
FORCEPROP 1 LAST OFFPAGE TRUE
J 2
(-9425 4150);
DISPLAY 0.872340 (-9425 4150);
PAINT AQUA (-9425 4150);
DISPLAY INVISIBLE (-9425 4150);
FORCEPROP 2 LAST CDS_LIB standard
J 2
(-9100 4275);
DISPLAY INVISIBLE (-9100 4275);
FORCEPROP 2 LAST PATH I96
J 0
(-8900 4325);
DISPLAY 1.021277 (-8900 4325);
DISPLAY INVISIBLE (-8900 4325);
FORCEADD GND..1
(-15950 4775);
FORCEPROP 3 LASTPIN (-15950 4825) SIG_NAME GND\g
J 0
(-15940 4835);
DISPLAY 0.659574 (-15940 4835);
PAINT MONO (-15940 4835);
DISPLAY INVISIBLE (-15940 4835);
FORCEPROP 1 LAST SIZE 1B
J 0
(-15875 4725);
DISPLAY 0.872340 (-15875 4725);
PAINT AQUA (-15875 4725);
DISPLAY INVISIBLE (-15875 4725);
FORCEPROP 1 LAST HDL_POWER GND
J 0
(-15950 4925);
DISPLAY 1.170213 (-15950 4925);
PAINT GREEN (-15950 4925);
DISPLAY INVISIBLE (-15950 4925);
FORCEPROP 1 LAST PATH I97
J 0
(-15875 4775);
DISPLAY 0.872340 (-15875 4775);
PAINT AQUA (-15875 4775);
DISPLAY INVISIBLE (-15875 4775);
FORCEPROP 2 LAST CDS_LIB logical_power
J 0
(-15950 4775);
DISPLAY INVISIBLE (-15950 4775);
FORCEADD DNS..2
(-14550 2850);
PAINT RED (-14550 2850);
FORCEPROP 1 LAST COMMENT_BODY TRUE
R 1
J 0
(-14475 2625);
DISPLAY 0.872340 (-14475 2625);
PAINT GREEN (-14475 2625);
DISPLAY INVISIBLE (-14475 2625);
FORCEPROP 2 LAST CDS_LIB mstr_misc
J 0
(-14550 2850);
DISPLAY INVISIBLE (-14550 2850);
FORCEADD QUANTA_TITLE_BLOCK_C..1
(-8625 -175);
FORCEPROP 0 LAST CDS_CON_LAST_MODIFIED Fri Aug 25 14:05:12 2023
J 0
(-10510 -160);
PAINT MONO (-10510 -160);
DISPLAY INVISIBLE (-10510 -160);
FORCEPROP 2 LAST CUSTOM_TXT_CDS <XR_PAGE_TITLE>
J 0
(-16515 5075);
DISPLAY 0.638298 (-16515 5075);
PAINT PINK (-16515 5075);
DISPLAY INVISIBLE (-16515 5075);
FORCEPROP 2 LAST CUSTOM_TXT_CDS <CON_LAST_MODIFIED>
J 0
(-10510 -160);
DISPLAY 0.978723 (-10510 -160);
FORCEPROP 2 LAST CUSTOM_TXT_CDS <Q_NUMBER>
J 0
(-10028 -72);
DISPLAY 1.212766 (-10028 -72);
FORCEPROP 2 LAST CUSTOM_TXT_CDS <CON_PAGE_NUM> OF <CON_TOTAL_PAGES>
J 0
(-9071 -157);
DISPLAY 0.978723 (-9071 -157);
FORCEPROP 2 LAST CUSTOM_TXT_CDS <Q_REV>
J 0
(-8809 -72);
DISPLAY 1.212766 (-8809 -72);
FORCEPROP 2 LAST CUSTOM_TXT_CDS <Q_PROJ>
J 0
(-11007 -73);
DISPLAY 1.212766 (-11007 -73);
FORCEPROP 1 LAST CUSTOM_TXT_CDS <NAME_2>
J 0
(-11800 -125);
FORCEPROP 1 LAST CUSTOM_TXT_CDS <NAME_1>
J 0
(-11800 0);
FORCEPROP 1 LAST Q_TITLE HSC MP5990 (1/4)
J 0
(-17991 -149);
DISPLAY 2.446809 (-17991 -149);
PAINT GREEN (-17991 -149);
FORCEPROP 1 LAST Q_DEPT 
J 1
(-12388 -126);
DISPLAY 1.957447 (-12388 -126);
PAINT GREEN (-12388 -126);
FORCEPROP 2 LAST CDS_XR_PAGE_TITLE CR-301 : @S9S_MB_2U_LIB.S9S_MB_2U(SCH_1):PAGE301
J 0
(-16515 5075);
DISPLAY 0.638298 (-16515 5075);
PAINT PINK (-16515 5075);
DISPLAY INVISIBLE (-16515 5075);
FORCEPROP 2 LAST PAGE_BORDER TRUE
J 0
(-16515 5075);
DISPLAY 0.638298 (-16515 5075);
PAINT PINK (-16515 5075);
DISPLAY INVISIBLE (-16515 5075);
FORCEPROP 2 LAST CDS_LIB pure_quanta
J 0
(-8625 -175);
PAINT MONO (-8625 -175);
DISPLAY INVISIBLE (-8625 -175);
FORCEPROP 1 LAST CDS_LMAN_SYM_OUTLINE -9475,6775,100,-125
J 0
(-8625 -175);
DISPLAY 0.468085 (-8625 -175);
PAINT GREEN (-8625 -175);
DISPLAY INVISIBLE (-8625 -175);
FORCEPROP 1 LAST COMMENT_BODY TRUE
J 0
(-8613 -188);
DISPLAY 0.978723 (-8613 -188);
PAINT GREEN (-8613 -188);
DISPLAY INVISIBLE (-8613 -188);
WIRE 16 -1 (-16650 4100)(-16650 4150);
WIRE 16 -1 (-15950 3500)(-15950 3475);
WIRE 16 -1 (-11350 3675)(-11350 3625);
WIRE 16 -1 (-11775 3675)(-11350 3675);
WIRE 16 -1 (-15425 4325)(-15425 4375);
WIRE 16 -1 (-15950 5525)(-15950 5600);
WIRE 16 -1 (-15950 5525)(-15425 5525);
WIRE 16 -1 (-15950 5150)(-15950 5525);
WIRE 16 -1 (-14475 750)(-14475 550);
WIRE 16 -1 (-16950 4925)(-16950 4850);
WIRE 16 -1 (-12725 1725)(-12725 1575);
WIRE 16 -1 (-12725 1725)(-13075 1725);
WIRE 16 -1 (-10350 2850)(-10350 2925);
WIRE 16 -1 (-9950 4900)(-9950 4825);
WIRE 16 -1 (-10300 5450)(-10300 5350);
WIRE 16 -1 (-9350 3350)(-9350 3425);
WIRE 16 -1 (-9275 3975)(-9275 3950);
WIRE 16 -1 (-9750 3975)(-9275 3975);
WIRE 16 -1 (-11225 2775)(-11225 2750);
WIRE 16 -1 (-11700 2000)(-11700 2050);
WIRE 16 -1 (-11700 2750)(-11700 2700);
WIRE 16 -1 (-11500 4425)(-11500 4475);
WIRE 16 -1 (-15050 2775)(-15050 2625);
WIRE 16 -1 (-13800 2725)(-13800 2675);
WIRE 16 -1 (-13800 2775)(-13800 2725);
WIRE 16 -1 (-13700 2725)(-13800 2725);
WIRE 16 -1 (-14575 2350)(-14575 2300);
WIRE 16 -1 (-15325 3500)(-15325 3475);
WIRE 16 -1 (-15950 4950)(-15950 4825);
WIRE 16 -1 (-17225 300)(-17225 225);
WIRE 16 -1 (-16000 250)(-16000 225);
WIRE 16 -1 (-16525 250)(-16000 250);
WIRE 16 -1 (-16000 425)(-16000 250);
WIRE 16 -1 (-15100 650)(-15100 550);
WIRE 16 -1 (-16800 1750)(-16800 1650);
WIRE 16 -1 (-16750 1750)(-16800 1750);
WIRE 16 -1 (-13500 1725)(-13500 1525);
WIRE 16 -1 (-13500 1725)(-13275 1725);
WIRE 16 -1 (-16775 3775)(-15500 3775);
FORCEPROP 2 LAST SIG_NAME SMB_SML1_PMBUS_HSC_SDA
J 0
(-16785 3785);
DISPLAY 0.723404 (-16785 3785);
WIRE 16 -1 (-16775 3875)(-15500 3875);
FORCEPROP 2 LAST SIG_NAME SMB_SML1_PMBUS_HSC_SCL
J 0
(-16785 3885);
DISPLAY 0.723404 (-16785 3885);
WIRE 16 -1 (-16450 3200)(-17475 3200);
FORCEPROP 2 LAST SIG_NAME IRQ_SML1_PMBUS_ALERT_N
J 0
(-17485 3210);
DISPLAY 0.723404 (-17485 3210);
WIRE 16 -1 (-13700 3675)(-15500 3675);
FORCEPROP 2 LAST SIG_NAME IRQ_SML1_PMBUS_ALERT
J 0
(-14485 3685);
DISPLAY 0.723404 (-14485 3685);
WIRE 16 -1 (-15500 3675)(-15500 3200);
WIRE 16 -1 (-15950 3275)(-15950 3200);
WIRE 16 -1 (-15500 3200)(-15950 3200);
WIRE 16 -1 (-16250 3200)(-15950 3200);
WIRE 16 -1 (-15975 3000)(-15325 3000);
WIRE 16 -1 (-15325 3000)(-15325 3350);
WIRE 16 -1 (-14925 3350)(-15325 3350);
FORCEPROP 2 LAST SIG_NAME HSC_EN
J 0
(-15960 3010);
DISPLAY 0.723404 (-15960 3010);
WIRE 16 -1 (-15975 2850)(-15200 2850);
FORCEPROP 2 LAST SIG_NAME HSC_ON
J 0
(-15960 2860);
DISPLAY 0.723404 (-15960 2860);
WIRE 16 -1 (-15200 2850)(-15200 3225);
WIRE 16 -1 (-15200 3225)(-14925 3225);
WIRE 16 2175 (-17125 2425)(-15900 2425);
WIRE 16 2175 (-15900 2425)(-15900 1525);
WIRE 16 2175 (-17125 2425)(-17125 1525);
WIRE 16 2175 (-17125 1525)(-15900 1525);
WIRE 16 -1 (-15425 4375)(-15425 4500);
WIRE 16 -1 (-14900 4375)(-15425 4375);
WIRE 16 -1 (-14900 4500)(-14900 4375);
WIRE 16 -1 (-13850 4375)(-13700 4375);
WIRE 16 -1 (-13850 4425)(-13850 4375);
WIRE 16 -1 (-13850 4425)(-13700 4425);
WIRE 16 -1 (-13850 4475)(-13850 4425);
WIRE 16 -1 (-13850 4475)(-13700 4475);
WIRE 16 -1 (-13850 4525)(-13850 4475);
WIRE 16 -1 (-13850 4525)(-13700 4525);
WIRE 16 -1 (-13850 4575)(-13850 4525);
WIRE 16 -1 (-13700 4575)(-13850 4575);
WIRE 16 -1 (-13850 4625)(-13850 4575);
WIRE 16 -1 (-13700 4625)(-13850 4625);
WIRE 16 -1 (-13850 4675)(-13850 4625);
WIRE 16 -1 (-13700 4675)(-13850 4675);
WIRE 16 -1 (-13850 4725)(-13850 4675);
WIRE 16 -1 (-13700 4725)(-13850 4725);
WIRE 16 -1 (-15425 5525)(-15425 5150);
WIRE 16 -1 (-13850 4775)(-13850 4725);
WIRE 16 -1 (-13700 4775)(-13850 4775);
WIRE 16 -1 (-13850 4825)(-13850 4775);
WIRE 16 -1 (-13700 4825)(-13850 4825);
WIRE 16 -1 (-13850 5525)(-15425 5525);
WIRE 16 -1 (-13850 5525)(-13850 4825);
WIRE 16 -1 (-13700 2775)(-13800 2775);
WIRE 16 -1 (-16525 350)(-16525 250);
WIRE 16 -1 (-11975 4475)(-11975 4575);
WIRE 16 -1 (-11500 4475)(-11975 4475);
WIRE 16 -1 (-11500 4575)(-11500 4475);
WIRE 16 -1 (-10650 2925)(-10650 3025);
WIRE 16 -1 (-10650 2925)(-10350 2925);
WIRE 16 -1 (-10175 2925)(-10350 2925);
WIRE 16 -1 (-10175 3050)(-10175 2925);
WIRE 16 -1 (-9725 4825)(-9725 4700);
WIRE 16 -1 (-9725 4825)(-9950 4825);
WIRE 16 -1 (-10150 4825)(-9950 4825);
WIRE 16 -1 (-10150 4700)(-10150 4825);
WIRE 16 -1 (-12550 4375)(-12400 4375);
WIRE 16 -1 (-12550 4425)(-12400 4425);
WIRE 16 -1 (-12400 4375)(-12400 4425);
WIRE 16 -1 (-12550 4475)(-12400 4475);
WIRE 16 -1 (-12400 4425)(-12400 4475);
WIRE 16 -1 (-12550 4525)(-12400 4525);
WIRE 16 -1 (-12400 4475)(-12400 4525);
WIRE 16 -1 (-12550 4575)(-12400 4575);
WIRE 16 -1 (-12400 4525)(-12400 4575);
WIRE 16 -1 (-12400 4575)(-12400 4625);
WIRE 16 -1 (-12550 4625)(-12400 4625);
WIRE 16 -1 (-12550 4675)(-12400 4675);
WIRE 16 -1 (-12400 4625)(-12400 4675);
WIRE 16 -1 (-12550 4725)(-12400 4725);
WIRE 16 -1 (-12400 4675)(-12400 4725);
WIRE 16 -1 (-12550 4775)(-12400 4775);
WIRE 16 -1 (-12400 4725)(-12400 4775);
WIRE 16 -1 (-12550 4825)(-12400 4825);
WIRE 16 -1 (-12400 4775)(-12400 4825);
WIRE 16 -1 (-12375 4825)(-12400 4825);
WIRE 16 -1 (-12375 4825)(-12375 5350);
WIRE 16 -1 (-12375 5350)(-12050 5350);
WIRE 16 -1 (-12050 5225)(-12050 5350);
WIRE 16 -1 (-12050 5350)(-10300 5350);
WIRE 16 -1 (-9825 3425)(-9825 3450);
WIRE 16 -1 (-9350 3425)(-9825 3425);
WIRE 16 -1 (-9350 3475)(-9350 3425);
WIRE 16 -1 (-15325 3475)(-14925 3475);
WIRE 16 -1 (-16650 4150)(-16650 4200);
WIRE 16 -1 (-17150 4150)(-16650 4150);
WIRE 16 -1 (-17150 4225)(-17150 4150);
WIRE 16 -1 (-14375 3575)(-13700 3575);
WIRE 16 -1 (-14375 3475)(-14375 3575);
FORCEPROP 2 LAST SIG_NAME HSC_VIN_UVW_N
J 0
(-14260 3585);
DISPLAY 0.723404 (-14260 3585);
WIRE 16 -1 (-14725 3475)(-14375 3475);
WIRE 16 -1 (-15300 3775)(-13700 3775);
FORCEPROP 2 LAST SIG_NAME SMB_SML1_PMBUS_HSC_R_SDA
J 0
(-14635 3785);
DISPLAY 0.723404 (-14635 3785);
WIRE 16 -1 (-14725 3350)(-14225 3350);
WIRE 16 -1 (-14225 3475)(-14225 3350);
WIRE 16 -1 (-13700 3475)(-14225 3475);
FORCEPROP 2 LAST SIG_NAME HSC_EN_R
J 0
(-14085 3485);
DISPLAY 0.723404 (-14085 3485);
WIRE 16 -1 (-11225 3075)(-11225 2975);
WIRE 16 -1 (-11225 3075)(-11150 3075);
WIRE 16 -1 (-12550 3075)(-11225 3075);
FORCEPROP 2 LAST SIG_NAME HSC_SS
J 0
(-12435 3085);
DISPLAY 0.808511 (-12435 3085);
WIRE 16 -1 (-14575 2550)(-14575 2650);
WIRE 16 -1 (-14575 2750)(-14575 2650);
WIRE 16 -1 (-14100 2650)(-14575 2650);
WIRE 16 -1 (-14100 2650)(-14100 2925);
FORCEPROP 2 LAST SIG_NAME HSC_ADDR
J 0
(-14085 2935);
DISPLAY 0.723404 (-14085 2935);
WIRE 16 -1 (-14100 2925)(-13700 2925);
WIRE 16 -1 (-15050 3075)(-15050 2975);
WIRE 16 -1 (-14575 3075)(-14575 2950);
WIRE 16 -1 (-14575 3075)(-15050 3075);
WIRE 16 -1 (-13700 3075)(-14575 3075);
FORCEPROP 2 LAST SIG_NAME HSC_VDD18
J 0
(-14110 3085);
DISPLAY 0.723404 (-14110 3085);
WIRE 16 -1 (-14725 3225)(-13700 3225);
FORCEPROP 2 LAST SIG_NAME HSC_ON_R
J 0
(-14085 3235);
DISPLAY 0.723404 (-14085 3235);
WIRE 16 -1 (-15300 3875)(-13700 3875);
FORCEPROP 2 LAST SIG_NAME SMB_SML1_PMBUS_HSC_L_SCL
J 0
(-14635 3885);
DISPLAY 0.723404 (-14635 3885);
WIRE 16 -1 (-9350 3775)(-9350 3675);
WIRE 16 -1 (-9150 3775)(-9350 3775);
WIRE 16 -1 (-9825 3650)(-9825 3775);
WIRE 16 -1 (-9350 3775)(-9825 3775);
WIRE 16 -1 (-12550 3775)(-9825 3775);
FORCEPROP 2 LAST SIG_NAME HSC_IMON
J 0
(-12435 3785);
DISPLAY 0.808511 (-12435 3785);
WIRE 16 -1 (-12550 3675)(-11975 3675);
FORCEPROP 2 LAST SIG_NAME HSC_CS
J 0
(-12435 3685);
DISPLAY 0.808511 (-12435 3685);
WIRE 16 -1 (-10175 3375)(-10175 3250);
WIRE 16 -1 (-10075 3375)(-10175 3375);
WIRE 16 -1 (-10650 3225)(-10650 3375);
WIRE 16 -1 (-10650 3375)(-10175 3375);
WIRE 16 -1 (-12550 3375)(-10650 3375);
FORCEPROP 2 LAST SIG_NAME HSC_VTEMP
J 0
(-12435 3385);
DISPLAY 0.808511 (-12435 3385);
WIRE 16 -1 (-10250 3975)(-9950 3975);
WIRE 16 -1 (-10250 3875)(-10250 3975);
WIRE 16 -1 (-12550 3875)(-10250 3875);
FORCEPROP 2 LAST SIG_NAME HSC_MODE
J 0
(-12435 3885);
DISPLAY 0.808511 (-12435 3885);
WIRE 16 -1 (-11700 4100)(-10775 4100);
WIRE 16 -1 (-11575 3975)(-11700 3975);
WIRE 16 -1 (-11700 3975)(-11700 4100);
WIRE 16 -1 (-12550 3975)(-11700 3975);
FORCEPROP 2 LAST SIG_NAME HSC_D_OC_R
J 0
(-12435 3985);
DISPLAY 0.808511 (-12435 3985);
WIRE 16 -1 (-11825 4275)(-10775 4275);
WIRE 16 -1 (-11825 4175)(-11825 4275);
WIRE 16 -1 (-11575 4175)(-11825 4175);
WIRE 16 -1 (-11825 4075)(-11825 4175);
WIRE 16 -1 (-12550 4075)(-11825 4075);
FORCEPROP 2 LAST SIG_NAME HSC_FAULT
J 0
(-12435 4085);
DISPLAY 0.808511 (-12435 4085);
WIRE 16 -1 (-11700 2400)(-11700 2500);
WIRE 16 -1 (-11700 2400)(-11250 2400);
WIRE 16 -1 (-11700 2250)(-11700 2350);
WIRE 16 -1 (-11700 2350)(-11700 2400);
WIRE 16 -1 (-12050 2350)(-11700 2350);
WIRE 16 -1 (-12050 2775)(-12050 2350);
WIRE 16 -1 (-12550 2775)(-12050 2775);
FORCEPROP 2 LAST SIG_NAME MB0_P12V_STBY_PWRGD
J 0
(-12435 2785);
DISPLAY 0.723404 (-12435 2785);
WIRE 16 -1 (-10575 4100)(-10150 4100);
WIRE 16 -1 (-10150 4100)(-9150 4100);
FORCEPROP 2 LAST SIG_NAME HSC_D_OC
J 0
(-9460 4110);
DISPLAY 0.808511 (-9460 4110);
WIRE 16 -1 (-10150 4500)(-10150 4100);
WIRE 16 -1 (-12550 4275)(-12075 4275);
WIRE 16 -1 (-12075 4275)(-12075 4900);
WIRE 16 -1 (-12075 4900)(-12050 4900);
WIRE 16 -1 (-12050 4900)(-12050 5025);
WIRE 16 -1 (-12050 4900)(-11975 4900);
WIRE 16 -1 (-11975 4775)(-11975 4900);
WIRE 16 -1 (-11500 4900)(-11975 4900);
WIRE 16 -1 (-11500 4900)(-11500 4775);
WIRE 16 -1 (-12550 2975)(-11925 2975);
FORCEPROP 2 LAST SIG_NAME HSC_FLT_TYPE
J 0
(-12435 2985);
DISPLAY 0.808511 (-12435 2985);
WIRE 16 -1 (-14300 4275)(-13700 4275);
WIRE 16 -1 (-14300 4825)(-14300 4275);
WIRE 16 -1 (-14900 4825)(-14900 4700);
WIRE 16 -1 (-14900 4825)(-14300 4825);
FORCEPROP 2 LAST SIG_NAME HSC_VSENSE
J 0
(-14185 4285);
DISPLAY 0.808511 (-14185 4285);
WIRE 16 -1 (-15425 4825)(-15425 4950);
WIRE 16 -1 (-15425 4825)(-14900 4825);
WIRE 16 -1 (-15425 4700)(-15425 4825);
WIRE 16 -1 (-17150 4425)(-17150 4575);
WIRE 16 -1 (-17150 4575)(-16950 4575);
WIRE 16 -1 (-16950 4650)(-16950 4575);
WIRE 16 -1 (-16950 4575)(-16650 4575);
WIRE 16 -1 (-16650 4400)(-16650 4575);
WIRE 16 -1 (-16125 4575)(-16650 4575);
WIRE 16 -1 (-16125 4075)(-16125 4575);
WIRE 16 -1 (-16125 4075)(-13950 4075);
FORCEPROP 2 LAST SIG_NAME HSC_VDD_R
J 0
(-14160 4085);
DISPLAY 0.808511 (-14160 4085);
WIRE 16 -1 (-13950 4075)(-13700 4075);
WIRE 16 -1 (-13950 4025)(-13950 4075);
WIRE 16 -1 (-13950 4025)(-13700 4025);
WIRE 16 -1 (-10575 4275)(-9725 4275);
WIRE 16 -1 (-9150 4275)(-9725 4275);
FORCEPROP 2 LAST SIG_NAME IRQ_HSC_FAULT_N
J 0
(-9660 4285);
DISPLAY 0.723404 (-9660 4285);
WIRE 16 -1 (-9725 4500)(-9725 4275);
WIRE 16 -1 (-12550 3275)(-11925 3275);
FORCEPROP 2 LAST SIG_NAME HSC_OCREF
J 0
(-12435 3285);
DISPLAY 0.808511 (-12435 3285);
WIRE 16 -1 (-16525 625)(-16525 550);
WIRE 16 -1 (-16200 625)(-16525 625);
WIRE 16 -1 (-16575 625)(-16525 625);
WIRE 16 -1 (-16575 850)(-16575 625);
WIRE 16 -1 (-17225 625)(-17225 500);
WIRE 16 -1 (-17350 625)(-17225 625);
FORCEPROP 2 LAST SIG_NAME PDB_PRSNT_N
J 0
(-17360 635);
DISPLAY 0.808511 (-17360 635);
PAINT WHITE (-17360 635);
WIRE 16 -1 (-16900 625)(-17225 625);
WIRE 16 -1 (-16575 625)(-16900 625);
WIRE 16 -1 (-16900 1800)(-16900 625);
WIRE 16 -1 (-16750 1800)(-16900 1800);
WIRE 16 -1 (-12550 3175)(-11925 3175);
FORCEPROP 2 LAST SIG_NAME HSC_SCREF
J 0
(-12435 3185);
DISPLAY 0.808511 (-12435 3185);
WIRE 16 -1 (-16000 825)(-16000 875);
WIRE 16 -1 (-16000 875)(-15100 875);
WIRE 16 -1 (-15100 850)(-15100 875);
WIRE 16 -1 (-15100 1350)(-15100 875);
WIRE 16 -1 (-15100 1350)(-15300 1350);
WIRE 16 -1 (-14475 1350)(-15100 1350);
FORCEPROP 2 LAST SIG_NAME HSC_EN
J 0
(-14585 1360);
DISPLAY 0.723404 (-14585 1360);
WIRE 16 -1 (-14475 1350)(-14375 1350);
WIRE 16 -1 (-14475 950)(-14475 1350);
WIRE 16 -1 (-16575 1050)(-16575 1350);
WIRE 16 -1 (-16575 1350)(-15775 1350);
WIRE 16 -1 (-15775 1350)(-15500 1350);
WIRE 16 -1 (-15775 1575)(-15775 1350);
WIRE 16 -1 (-15200 1575)(-15775 1575);
FORCEPROP 2 LAST SIG_NAME P12V_PSU_FUSE
J 0
(-15660 1585);
DISPLAY 0.638298 (-15660 1585);
PAINT WHITE (-15660 1585);
DOT 1 (-17225 625);
DOT 1 (-16575 625);
DOT 1 (-16900 625);
DOT 1 (-16525 625);
DOT 1 (-16000 250);
DOT 1 (-16650 4150);
DOT 1 (-16950 4575);
DOT 1 (-16650 4575);
DOT 1 (-15775 1350);
DOT 1 (-15100 875);
DOT 1 (-15100 1350);
DOT 1 (-14475 1350);
DOT 1 (-14575 2650);
DOT 1 (-15950 3200);
DOT 1 (-15950 5525);
DOT 1 (-15425 5525);
DOT 1 (-14900 4825);
DOT 1 (-13950 4075);
DOT 1 (-13850 4425);
DOT 1 (-13850 4475);
DOT 1 (-13850 4525);
DOT 1 (-13850 4625);
DOT 1 (-13850 4675);
DOT 1 (-13850 4725);
DOT 1 (-13850 4775);
DOT 1 (-12400 4475);
DOT 1 (-12400 4525);
DOT 1 (-12400 4625);
DOT 1 (-12400 4575);
DOT 1 (-12400 4675);
DOT 1 (-12400 4725);
DOT 1 (-12400 4775);
DOT 1 (-11225 3075);
DOT 1 (-11825 4175);
DOT 1 (-11500 4475);
DOT 1 (-10650 3375);
DOT 1 (-10350 2925);
DOT 1 (-10175 3375);
DOT 1 (-13850 4825);
DOT 1 (-12400 4825);
DOT 1 (-12050 4900);
DOT 1 (-12050 5350);
DOT 1 (-9950 4825);
DOT 1 (-9350 3425);
DOT 1 (-9350 3775);
DOT 1 (-9825 3775);
DOT 1 (-9725 4275);
DOT 1 (-11975 4900);
DOT 1 (-10150 4100);
DOT 1 (-11700 2350);
DOT 1 (-11700 2400);
DOT 1 (-12400 4425);
DOT 1 (-15425 4375);
DOT 1 (-15425 4825);
DOT 1 (-13850 4575);
DOT 1 (-11700 3975);
DOT 1 (-14575 3075);
DOT 1 (-13800 2725);
FORCENOTE
20211203 CHANGE JP4003 CONNECT 
(-17450 2475) 0;
DISPLAY LEFT (-17450 2475);
DISPLAY 1.595745 (-17450 2475);
PAINT PINK (-17450 2475);
FORCENOTE
JUMPER 1-2
(-16625 2200) 0;
DISPLAY LEFT (-16625 2200);
DISPLAY 1.276596 (-16625 2200);
PAINT WHITE (-16625 2200);
FORCENOTE
20211112 MODIFY FOR GT
(-16150 6250) 0;
DISPLAY LEFT (-16150 6250);
DISPLAY 2.510638 (-16150 6250);
PAINT PINK (-16150 6250);
FORCENOTE
OCP=240A
(-17850 6209) 0;
DISPLAY LEFT (-17850 6209);
DISPLAY 1.595745 (-17850 6209);
FORCENOTE
LATCH OFF MODE
(-17825 5875) 0;
DISPLAY LEFT (-17825 5875);
DISPLAY 1.021277 (-17825 5875);
FORCENOTE
ADDRESS 0X20
(-17825 5941) 0;
DISPLAY LEFT (-17825 5941);
DISPLAY 1.021277 (-17825 5941);
FORCENOTE
UV =10.091V
(-17825 6000) 0;
DISPLAY LEFT (-17825 6000);
DISPLAY 1.021277 (-17825 6000);
FORCENOTE
OV =14.333V
(-17825 6050) 0;
DISPLAY LEFT (-17825 6050);
DISPLAY 1.021277 (-17825 6050);
FORCENOTE
OCW=220A
(-17850 6134) 0;
DISPLAY LEFT (-17850 6134);
DISPLAY 1.595745 (-17850 6134);
FORCENOTE
FPH=220A
(-17125 6134) 0;
DISPLAY LEFT (-17125 6134);
DISPLAY 1.595745 (-17125 6134);
FORCENOTE
HOT SWAT CIRCUIT
(-17846 6313) 0;
DISPLAY LEFT (-17846 6313);
DISPLAY 2.000000 (-17846 6313);
FORCENOTE
EN>1.2V ON
(-14200 3375) 0;
DISPLAY LEFT (-14200 3375);
DISPLAY 1.021277 (-14200 3375);
FORCENOTE
EN<0.95V OFF
(-14200 3300) 0;
DISPLAY LEFT (-14200 3300);
DISPLAY 1.021277 (-14200 3300);
FORCENOTE
VOUT SLEW RATE: 2V/MS
(-10900 2484) 0;
DISPLAY LEFT (-10900 2484);
DISPLAY 1.021277 (-10900 2484);
FORCENOTE
SOFT START TIME=6MS.
(-10900 2550) 0;
DISPLAY LEFT (-10900 2550);
DISPLAY 1.021277 (-10900 2550);
FORCENOTE
7BITS ADDRESS 0X20H
(-13575 2450) 0;
DISPLAY LEFT (-13575 2450);
DISPLAY 1.021277 (-13575 2450);
QUIT
